FILE_TYPE = MACRO_DRAWING;
SET COLOR_WIRE YELLOW;
SET COLOR_PROP MONO;
SET COLOR_DOT WHITE;
SET COLOR_ARC YELLOW;
SET COLOR_BODY GREEN;
SET COLOR_NOTE MONO;
SET PROP_DISPLAY VALUE;
SET PAGE_NUMBER P155;
FORCEADD CAP_A..1
(-4100 1050);
FORCEPROP 1 LAST LOCATION C9A1
J 0
(-4050 1150);
DISPLAY 0.617021 (-4050 1150);
PAINT AQUA (-4050 1150);
FORCEPROP 1 LAST VALUE 0.1UF
J 0
(-4050 1100);
DISPLAY 0.617021 (-4050 1100);
PAINT SKYBLUE (-4050 1100);
FORCEPROP 1 LAST MATERIAL X7R
J 0
(-4050 950);
DISPLAY 0.617021 (-4050 950);
PAINT SKYBLUE (-4050 950);
FORCEPROP 1 LAST VOLTAGE 16V
J 0
(-4050 1050);
DISPLAY 0.617021 (-4050 1050);
PAINT SKYBLUE (-4050 1050);
FORCEPROP 1 LAST PACK_TYPE 0402V
J 0
(-4050 850);
DISPLAY 0.617021 (-4050 850);
PAINT SKYBLUE (-4050 850);
FORCEPROP 1 LAST TOLERANCE 10%
J 0
(-4050 1000);
DISPLAY 0.617021 (-4050 1000);
PAINT SKYBLUE (-4050 1000);
FORCEPROP 1 LAST PART_NUMBER A36096-030
J 0
(-4050 900);
DISPLAY 0.617021 (-4050 900);
PAINT BLUE (-4050 900);
FORCEPROP 2 LAST BOM_COST DEBUG
J 0
(-4050 1250);
DISPLAY 1.021277 (-4050 1250);
PAINT ORANGE (-4050 1250);
DISPLAY INVISIBLE (-4050 1250);
FORCEPROP 2 LAST CDS_SEC 1
J 0
(-4050 1250);
DISPLAY 1.021277 (-4050 1250);
PAINT ORANGE (-4050 1250);
DISPLAY INVISIBLE (-4050 1250);
FORCEPROP 2 LAST $SEC 1
J 0
(-4050 1250);
DISPLAY 0.680851 (-4050 1250);
PAINT MONO (-4050 1250);
DISPLAY INVISIBLE (-4050 1250);
FORCEPROP 1 LAST PATH I127
J 0
(-4050 1200);
DISPLAY 0.978723 (-4050 1200);
PAINT WHITE (-4050 1200);
DISPLAY INVISIBLE (-4050 1200);
FORCEPROP 2 LAST ROOM BMC_DEBUG_HEADER
J 0
(-4050 1200);
DISPLAY 1.021277 (-4050 1200);
PAINT ORANGE (-4050 1200);
DISPLAY INVISIBLE (-4050 1200);
FORCEPROP 2 LAST CDS_LOCATION C9A1
J 0
(-4050 1150);
DISPLAY 0.617021 (-4050 1150);
PAINT AQUA (-4050 1150);
DISPLAY INVISIBLE (-4050 1150);
FORCEPROP 2 LAST CDS_LIB dev_discrete
J 0
(-4100 1050);
PAINT ORANGE (-4100 1050);
DISPLAY INVISIBLE (-4100 1050);
FORCEPROP 1 LASTPIN (-4100 1150) $PN 1
J 0
(-4090 1130);
DISPLAY 0.787234 (-4090 1130);
PAINT ORANGE (-4090 1130);
DISPLAY INVISIBLE (-4090 1130);
FORCEPROP 1 LASTPIN (-4100 950) $PN 2
J 0
(-4090 930);
DISPLAY 0.787234 (-4090 930);
PAINT ORANGE (-4090 930);
DISPLAY INVISIBLE (-4090 930);
FORCEADD GND..1
(-4100 825);
FORCEPROP 3 LASTPIN (-4100 875) SIG_NAME GND\g
J 0
(-4090 885);
DISPLAY 0.659574 (-4090 885);
PAINT MONO (-4090 885);
DISPLAY INVISIBLE (-4090 885);
FORCEPROP 1 LAST HDL_POWER GND
J 0
(-4100 975);
DISPLAY 0.872340 (-4100 975);
PAINT GREEN (-4100 975);
DISPLAY INVISIBLE (-4100 975);
FORCEPROP 1 LAST PATH I128
J 0
(-4025 825);
DISPLAY 0.872340 (-4025 825);
PAINT AQUA (-4025 825);
DISPLAY INVISIBLE (-4025 825);
FORCEPROP 1 LAST SIZE 1B
J 0
(-4025 775);
DISPLAY 0.872340 (-4025 775);
PAINT AQUA (-4025 775);
DISPLAY INVISIBLE (-4025 775);
FORCEPROP 1 LAST BODY_TYPE PLUMBING
J 0
(-4145 782);
DISPLAY 0.340426 (-4145 782);
PAINT GREEN (-4145 782);
DISPLAY INVISIBLE (-4145 782);
FORCEPROP 2 LAST CDS_LIB mstr_symbols
J 0
(-4100 825);
PAINT ORANGE (-4100 825);
DISPLAY INVISIBLE (-4100 825);
FORCEPROP 1 LAST VOLTAGE 0.0V
J 0
(-4145 782);
DISPLAY 0.340426 (-4145 782);
PAINT SKYBLUE (-4145 782);
DISPLAY INVISIBLE (-4145 782);
FORCEADD FUSE..1
(-4275 2625);
FORCEPROP 0 LAST CONFIG 069.50018.0001
J 0
(-4425 2775);
DISPLAY 0.638298 (-4425 2775);
PAINT BROWN (-4425 2775);
DISPLAY BOTH (-4425 2775);
FORCEPROP 1 LAST LOCATION F1L1
J 0
(-4425 2725);
DISPLAY 0.617021 (-4425 2725);
PAINT AQUA (-4425 2725);
FORCEPROP 1 LAST MATERIAL IC
J 0
(-4425 2675);
DISPLAY 0.617021 (-4425 2675);
PAINT SKYBLUE (-4425 2675);
FORCEPROP 1 LASTPIN (-4425 2625) $PN 1
J 0
(-4440 2635);
DISPLAY 0.617021 (-4440 2635);
PAINT ORANGE (-4440 2635);
FORCEPROP 1 LASTPIN (-4125 2625) $PN 2
J 0
(-4140 2635);
DISPLAY 0.617021 (-4140 2635);
PAINT ORANGE (-4140 2635);
FORCEPROP 1 LAST PART_NUMBER H45581-001
J 0
(-4275 2725);
DISPLAY 0.617021 (-4275 2725);
PAINT BLUE (-4275 2725);
FORCEPROP 1 LAST PATH I129
J 0
(-3975 2675);
DISPLAY 0.978723 (-3975 2675);
PAINT BLUE (-3975 2675);
DISPLAY INVISIBLE (-3975 2675);
FORCEPROP 2 LAST CDS_LIB mstr_discrete
J 0
(-4275 2625);
PAINT MONO (-4275 2625);
DISPLAY INVISIBLE (-4275 2625);
FORCEPROP 1 LAST PACK_TYPE SMT
J 0
(-4425 2775);
DISPLAY 0.978723 (-4425 2775);
PAINT SKYBLUE (-4425 2775);
DISPLAY INVISIBLE (-4425 2775);
FORCEPROP 2 LAST SEC_TYPE SMT
J 0
(-4425 2775);
DISPLAY 1.021277 (-4425 2775);
PAINT ORANGE (-4425 2775);
DISPLAY INVISIBLE (-4425 2775);
FORCEPROP 2 LAST BOM_COST DEBUG
J 0
(-4425 2825);
DISPLAY 1.021277 (-4425 2825);
PAINT ORANGE (-4425 2825);
DISPLAY INVISIBLE (-4425 2825);
FORCEPROP 2 LAST SEC 1
J 0
(-4425 2775);
PAINT MONO (-4425 2775);
DISPLAY INVISIBLE (-4425 2775);
FORCEPROP 2 LAST CDS_LOCATION F1L1
J 0
(-4425 2725);
DISPLAY 0.617021 (-4425 2725);
PAINT AQUA (-4425 2725);
DISPLAY INVISIBLE (-4425 2725);
FORCEPROP 2 LAST ROOM BMC_DEBUG_HEADER
J 0
(-4425 2775);
DISPLAY 1.021277 (-4425 2775);
PAINT ORANGE (-4425 2775);
DISPLAY INVISIBLE (-4425 2775);
FORCEADD RES..2
(-5950 2575);
FORCEPROP 1 LASTPIN (-5950 2475) $PN 2
J 0
(-5945 2485);
DISPLAY 0.617021 (-5945 2485);
PAINT ORANGE (-5945 2485);
FORCEPROP 1 LASTPIN (-5950 2675) $PN 1
J 0
(-5945 2637);
DISPLAY 0.617021 (-5945 2637);
PAINT ORANGE (-5945 2637);
FORCEPROP 1 LAST LOCATION R1L9
J 0
(-5905 2700);
DISPLAY 0.617021 (-5905 2700);
PAINT AQUA (-5905 2700);
FORCEPROP 1 LAST WATTAGE 1/16W
J 0
(-5910 2550);
DISPLAY 0.617021 (-5910 2550);
PAINT SKYBLUE (-5910 2550);
FORCEPROP 1 LAST TOLERANCE 1%
J 0
(-5905 2600);
DISPLAY 0.617021 (-5905 2600);
PAINT SKYBLUE (-5905 2600);
FORCEPROP 1 LAST VALUE 100.0K
J 0
(-5905 2650);
DISPLAY 0.617021 (-5905 2650);
PAINT SKYBLUE (-5905 2650);
FORCEPROP 1 LAST MATERIAL CHIP
J 0
(-5910 2500);
DISPLAY 0.617021 (-5910 2500);
PAINT SKYBLUE (-5910 2500);
FORCEPROP 1 LAST PACK_TYPE 0402
J 0
(-5910 2400);
DISPLAY 0.617021 (-5910 2400);
PAINT SKYBLUE (-5910 2400);
FORCEPROP 1 LAST PART_NUMBER G21796-010
J 0
(-5910 2450);
DISPLAY 0.617021 (-5910 2450);
PAINT BLUE (-5910 2450);
FORCEPROP 2 LAST BOM_COST DEBUG
J 0
(-5900 2800);
DISPLAY 1.021277 (-5900 2800);
PAINT ORANGE (-5900 2800);
DISPLAY INVISIBLE (-5900 2800);
FORCEPROP 2 LAST SEC_TYPE 0402
J 0
(-5900 2800);
DISPLAY 1.021277 (-5900 2800);
PAINT ORANGE (-5900 2800);
DISPLAY INVISIBLE (-5900 2800);
FORCEPROP 2 LAST SEC 1
J 0
(-5900 2800);
DISPLAY 0.680851 (-5900 2800);
PAINT MONO (-5900 2800);
DISPLAY INVISIBLE (-5900 2800);
FORCEPROP 1 LAST PATH I130
J 0
(-5900 2750);
DISPLAY 0.978723 (-5900 2750);
PAINT WHITE (-5900 2750);
DISPLAY INVISIBLE (-5900 2750);
FORCEPROP 2 LAST ROOM BMC_DEBUG_HEADER
J 0
(-5900 2750);
DISPLAY 1.021277 (-5900 2750);
PAINT ORANGE (-5900 2750);
DISPLAY INVISIBLE (-5900 2750);
FORCEPROP 2 LAST CDS_LOCATION R1L9
J 0
(-5905 2700);
DISPLAY 0.617021 (-5905 2700);
PAINT AQUA (-5905 2700);
DISPLAY INVISIBLE (-5905 2700);
FORCEPROP 2 LAST CDS_LIB mstr_discrete
J 0
(-5950 2575);
PAINT ORANGE (-5950 2575);
DISPLAY INVISIBLE (-5950 2575);
FORCEADD CONN14_H54902001..1
(-4450 1500);
FORCEPROP 2 LASTPIN (-4150 1300) $PN 14
J 0
(-4140 1310);
DISPLAY 0.617021 (-4140 1310);
PAINT MONO (-4140 1310);
FORCEPROP 2 LASTPIN (-4750 1400) $PN 9
J 2
(-4760 1410);
DISPLAY 0.617021 (-4760 1410);
PAINT MONO (-4760 1410);
FORCEPROP 1 LAST PART_NUMBER H54902-001
J 0
(-4700 1200);
DISPLAY 0.617021 (-4700 1200);
PAINT BLUE (-4700 1200);
FORCEPROP 1 LAST LOCATION J9A2
J 0
(-4700 1850);
DISPLAY 0.617021 (-4700 1850);
PAINT AQUA (-4700 1850);
FORCEPROP 1 LAST MATERIAL CONN
J 0
(-4700 1800);
DISPLAY 0.617021 (-4700 1800);
PAINT SKYBLUE (-4700 1800);
FORCEPROP 2 LASTPIN (-4150 1550) $PN 4
J 0
(-4140 1560);
DISPLAY 0.617021 (-4140 1560);
PAINT MONO (-4140 1560);
FORCEPROP 2 LASTPIN (-4150 1600) $PN 2
J 0
(-4140 1610);
DISPLAY 0.617021 (-4140 1610);
PAINT MONO (-4140 1610);
FORCEPROP 2 LASTPIN (-4150 1500) $PN 6
J 0
(-4140 1510);
DISPLAY 0.617021 (-4140 1510);
PAINT MONO (-4140 1510);
FORCEPROP 2 LASTPIN (-4150 1400) $PN 10
J 0
(-4140 1410);
DISPLAY 0.617021 (-4140 1410);
PAINT MONO (-4140 1410);
FORCEPROP 2 LASTPIN (-4150 1450) $PN 8
J 0
(-4140 1460);
DISPLAY 0.617021 (-4140 1460);
PAINT MONO (-4140 1460);
FORCEPROP 2 LASTPIN (-4150 1350) $PN 12
J 0
(-4140 1360);
DISPLAY 0.617021 (-4140 1360);
PAINT MONO (-4140 1360);
FORCEPROP 2 LASTPIN (-4750 1550) $PN 3
J 2
(-4760 1560);
DISPLAY 0.617021 (-4760 1560);
PAINT MONO (-4760 1560);
FORCEPROP 2 LASTPIN (-4750 1500) $PN 5
J 2
(-4760 1510);
DISPLAY 0.617021 (-4760 1510);
PAINT MONO (-4760 1510);
FORCEPROP 2 LASTPIN (-4750 1450) $PN 7
J 2
(-4760 1460);
DISPLAY 0.617021 (-4760 1460);
PAINT MONO (-4760 1460);
FORCEPROP 2 LASTPIN (-4750 1300) $PN 13
J 2
(-4760 1310);
DISPLAY 0.617021 (-4760 1310);
PAINT MONO (-4760 1310);
FORCEPROP 2 LASTPIN (-4750 1350) $PN 11
J 2
(-4760 1360);
DISPLAY 0.617021 (-4760 1360);
PAINT MONO (-4760 1360);
FORCEPROP 2 LASTPIN (-4750 1600) $PN 1
J 2
(-4760 1610);
DISPLAY 0.617021 (-4760 1610);
PAINT MONO (-4760 1610);
FORCEPROP 0 LAST BOM_COST DEBUG
J 0
(-4700 2050);
DISPLAY 1.021277 (-4700 2050);
PAINT ORANGE (-4700 2050);
DISPLAY INVISIBLE (-4700 2050);
FORCEPROP 1 LAST PATH I171
J 0
(-4400 1800);
PAINT GREEN (-4400 1800);
DISPLAY INVISIBLE (-4400 1800);
FORCEPROP 2 LAST $SEC 1
J 0
(-4700 1900);
PAINT MONO (-4700 1900);
DISPLAY INVISIBLE (-4700 1900);
FORCEPROP 1 LAST PACK_TYPE PIP
J 0
(-4700 1900);
PAINT SKYBLUE (-4700 1900);
DISPLAY INVISIBLE (-4700 1900);
FORCEPROP 2 LAST CDS_SEC 1
J 0
(-4700 1900);
PAINT MONO (-4700 1900);
DISPLAY INVISIBLE (-4700 1900);
FORCEPROP 2 LAST CDS_LOCATION J9A2
J 0
(-4700 1850);
DISPLAY 0.617021 (-4700 1850);
PAINT AQUA (-4700 1850);
DISPLAY INVISIBLE (-4700 1850);
FORCEPROP 0 LAST ROOM BMC_DEBUG_HEADER
J 0
(-4700 1950);
DISPLAY 1.021277 (-4700 1950);
PAINT ORANGE (-4700 1950);
DISPLAY INVISIBLE (-4700 1950);
FORCEPROP 2 LAST CDS_LIB mstr_conn
J 0
(-4450 1500);
PAINT ORANGE (-4450 1500);
DISPLAY INVISIBLE (-4450 1500);
FORCEPROP 1 LAST CDS_LMAN_SYM_OUTLINE -250,250,250,-250
J 0
(-4450 1500);
DISPLAY 0.468085 (-4450 1500);
PAINT GREEN (-4450 1500);
DISPLAY INVISIBLE (-4450 1500);
FORCEADD TTL1G07_A..1
(-2100 1400);
FORCEPROP 1 LAST VALUE 74LVC1G07
J 1
(-2100 1500);
DISPLAY 0.617021 (-2100 1500);
PAINT SKYBLUE (-2100 1500);
FORCEPROP 1 LAST MATERIAL IC
J 0
(-2150 1550);
DISPLAY 0.617021 (-2150 1550);
PAINT SKYBLUE (-2150 1550);
FORCEPROP 1 LAST LOCATION U9A1
J 0
(-2150 1600);
DISPLAY 0.617021 (-2150 1600);
PAINT AQUA (-2150 1600);
FORCEPROP 2 LASTPIN (-2200 1400) $PN 2
J 2
(-2210 1410);
DISPLAY 0.617021 (-2210 1410);
PAINT ORANGE (-2210 1410);
FORCEPROP 2 LASTPIN (-1950 1400) $PN 4
J 0
(-1940 1410);
DISPLAY 0.617021 (-1940 1410);
PAINT ORANGE (-1940 1410);
FORCEPROP 1 LAST PART_NUMBER C88419-001
J 0
(-2150 1265);
DISPLAY 0.617021 (-2150 1265);
PAINT BLUE (-2150 1265);
FORCEPROP 1 LAST POWER_GROUP VCC=P3V3_STBY;GND=GND
J 1
(-2150 1210);
DISPLAY 0.617021 (-2150 1210);
PAINT ORANGE (-2150 1210);
FORCEPROP 1 LAST PATH I178
J 0
(-2050 1450);
DISPLAY 0.978723 (-2050 1450);
PAINT WHITE (-2050 1450);
DISPLAY INVISIBLE (-2050 1450);
FORCEPROP 2 LAST CDS_LIB mstr_ttl
J 0
(-2100 1400);
PAINT ORANGE (-2100 1400);
DISPLAY INVISIBLE (-2100 1400);
FORCEPROP 0 LAST ROOM BMC_DEBUG_HEADER
J 0
(-2150 1700);
DISPLAY 1.021277 (-2150 1700);
PAINT ORANGE (-2150 1700);
DISPLAY INVISIBLE (-2150 1700);
FORCEPROP 2 LAST CDS_LOCATION U9A1
J 0
(-2150 1600);
DISPLAY 0.617021 (-2150 1600);
PAINT AQUA (-2150 1600);
DISPLAY INVISIBLE (-2150 1600);
FORCEPROP 2 LAST SEC 1
J 0
(-2150 1650);
DISPLAY 0.680851 (-2150 1650);
PAINT MONO (-2150 1650);
DISPLAY INVISIBLE (-2150 1650);
FORCEPROP 2 LAST SEC_TYPE SOP
J 0
(-2150 1650);
DISPLAY 1.021277 (-2150 1650);
PAINT ORANGE (-2150 1650);
DISPLAY INVISIBLE (-2150 1650);
FORCEPROP 0 LAST BOM_COST DEBUG
J 0
(-2150 1800);
DISPLAY 1.021277 (-2150 1800);
PAINT ORANGE (-2150 1800);
DISPLAY INVISIBLE (-2150 1800);
FORCEPROP 1 LAST PACK_TYPE SOP
J 0
(-2150 1650);
DISPLAY 0.978723 (-2150 1650);
PAINT SKYBLUE (-2150 1650);
DISPLAY INVISIBLE (-2150 1650);
FORCEADD GND..1
(-5950 1800);
FORCEPROP 3 LASTPIN (-5950 1850) SIG_NAME GND\g
J 0
(-5940 1860);
DISPLAY 0.659574 (-5940 1860);
PAINT MONO (-5940 1860);
DISPLAY INVISIBLE (-5940 1860);
FORCEPROP 1 LAST BODY_TYPE PLUMBING
J 0
(-5995 1757);
DISPLAY 0.340426 (-5995 1757);
PAINT GREEN (-5995 1757);
DISPLAY INVISIBLE (-5995 1757);
FORCEPROP 1 LAST VOLTAGE 0.0V
J 0
(-5995 1757);
DISPLAY 0.340426 (-5995 1757);
PAINT SKYBLUE (-5995 1757);
DISPLAY INVISIBLE (-5995 1757);
FORCEPROP 1 LAST SIZE 1B
J 0
(-5875 1750);
DISPLAY 0.872340 (-5875 1750);
PAINT AQUA (-5875 1750);
DISPLAY INVISIBLE (-5875 1750);
FORCEPROP 2 LAST CDS_LIB mstr_symbols
J 0
(-5950 1800);
PAINT ORANGE (-5950 1800);
DISPLAY INVISIBLE (-5950 1800);
FORCEPROP 1 LAST HDL_POWER GND
J 0
(-5950 1950);
DISPLAY 0.872340 (-5950 1950);
PAINT GREEN (-5950 1950);
DISPLAY INVISIBLE (-5950 1950);
FORCEPROP 1 LAST PATH I180
J 0
(-5875 1800);
DISPLAY 0.872340 (-5875 1800);
PAINT AQUA (-5875 1800);
DISPLAY INVISIBLE (-5875 1800);
FORCEADD OFFPAGE..1
(-7700 2000);
FORCEPROP 2 LAST $XR0 190 
J 0
(-7952 2000);
DISPLAY 0.638298 (-7952 2000);
PAINT MONO (-7952 2000);
FORCEPROP 2 LAST PATH I182
J 0
(-7650 2075);
DISPLAY 1.021277 (-7650 2075);
PAINT ORANGE (-7650 2075);
DISPLAY INVISIBLE (-7650 2075);
FORCEPROP 2 LAST CDS_LIB mstr_standard
J 0
(-7700 2000);
PAINT ORANGE (-7700 2000);
DISPLAY INVISIBLE (-7700 2000);
FORCEPROP 1 LAST OFFPAGE TRUE
J 0
(-7375 1875);
DISPLAY 0.872340 (-7375 1875);
PAINT GREEN (-7375 1875);
DISPLAY INVISIBLE (-7375 1875);
FORCEPROP 1 LAST COMMENT_BODY TRUE
J 0
(-7575 1900);
DISPLAY 0.872340 (-7575 1900);
PAINT GREEN (-7575 1900);
DISPLAY INVISIBLE (-7575 1900);
FORCEADD P3V3_STBY..1
(-1550 3325);
FORCEPROP 3 LASTPIN (-1550 3275) SIG_NAME P3V3_STBY\g
J 0
(-1540 3285);
DISPLAY 0.659574 (-1540 3285);
PAINT MONO (-1540 3285);
DISPLAY INVISIBLE (-1540 3285);
FORCEPROP 1 LAST PATH I183
J 0
(-1505 3327);
DISPLAY 0.340426 (-1505 3327);
PAINT GREEN (-1505 3327);
DISPLAY INVISIBLE (-1505 3327);
FORCEPROP 1 LAST SIZE 1B
J 0
(-1505 3347);
DISPLAY 0.340426 (-1505 3347);
PAINT GREEN (-1505 3347);
DISPLAY INVISIBLE (-1505 3347);
FORCEPROP 2 LAST CDS_LIB mstr_symbols
J 0
(-1550 3325);
PAINT ORANGE (-1550 3325);
DISPLAY INVISIBLE (-1550 3325);
FORCEPROP 1 LAST BODY_TYPE PLUMBING
J 0
(-1595 3282);
DISPLAY 0.340426 (-1595 3282);
PAINT GREEN (-1595 3282);
DISPLAY INVISIBLE (-1595 3282);
FORCEPROP 1 LAST VOLTAGE 3.3V
J 0
(-1595 3282);
DISPLAY 0.340426 (-1595 3282);
PAINT SKYBLUE (-1595 3282);
DISPLAY INVISIBLE (-1595 3282);
FORCEPROP 1 LAST HDL_POWER P3V3_STBY
J 0
(-1850 3200);
DISPLAY 0.872340 (-1850 3200);
PAINT ORANGE (-1850 3200);
DISPLAY INVISIBLE (-1850 3200);
FORCEADD CAP_A..1
(-1550 3025);
FORCEPROP 1 LAST PACK_TYPE 0402V
J 0
(-1500 2825);
DISPLAY 0.617021 (-1500 2825);
PAINT SKYBLUE (-1500 2825);
FORCEPROP 1 LAST PART_NUMBER A36096-030
J 0
(-1500 2875);
DISPLAY 0.617021 (-1500 2875);
PAINT BLUE (-1500 2875);
FORCEPROP 1 LAST VALUE 0.1UF
J 0
(-1500 3075);
DISPLAY 0.617021 (-1500 3075);
PAINT SKYBLUE (-1500 3075);
FORCEPROP 1 LAST LOCATION C1T56
J 0
(-1500 3125);
DISPLAY 0.617021 (-1500 3125);
PAINT AQUA (-1500 3125);
FORCEPROP 1 LASTPIN (-1550 3125) $PN 1
J 0
(-1540 3105);
DISPLAY 0.617021 (-1540 3105);
PAINT ORANGE (-1540 3105);
FORCEPROP 1 LAST MATERIAL X7R
J 0
(-1500 2925);
DISPLAY 0.617021 (-1500 2925);
PAINT SKYBLUE (-1500 2925);
FORCEPROP 1 LASTPIN (-1550 2925) $PN 2
J 0
(-1540 2905);
DISPLAY 0.617021 (-1540 2905);
PAINT ORANGE (-1540 2905);
FORCEPROP 1 LAST TOLERANCE 10%
J 0
(-1500 2975);
DISPLAY 0.617021 (-1500 2975);
PAINT SKYBLUE (-1500 2975);
FORCEPROP 1 LAST VOLTAGE 16V
J 0
(-1500 3025);
DISPLAY 0.617021 (-1500 3025);
PAINT SKYBLUE (-1500 3025);
FORCEPROP 2 LAST BOM_COST DEBUG
J 0
(-1500 3225);
DISPLAY 1.021277 (-1500 3225);
PAINT ORANGE (-1500 3225);
DISPLAY INVISIBLE (-1500 3225);
FORCEPROP 2 LAST SEC_TYPE 0402V
J 0
(-1500 3225);
DISPLAY 1.021277 (-1500 3225);
PAINT ORANGE (-1500 3225);
DISPLAY INVISIBLE (-1500 3225);
FORCEPROP 1 LAST PATH I184
J 0
(-1500 3175);
DISPLAY 0.978723 (-1500 3175);
PAINT WHITE (-1500 3175);
DISPLAY INVISIBLE (-1500 3175);
FORCEPROP 2 LAST ROOM BMC_DEBUG_HEADER
J 0
(-1500 3175);
DISPLAY 1.021277 (-1500 3175);
PAINT ORANGE (-1500 3175);
DISPLAY INVISIBLE (-1500 3175);
FORCEPROP 2 LAST CDS_SEC 1
J 0
(-1500 3175);
PAINT ORANGE (-1500 3175);
DISPLAY INVISIBLE (-1500 3175);
FORCEPROP 2 LAST SEC 1
J 0
(-1500 3175);
DISPLAY 0.680851 (-1500 3175);
PAINT MONO (-1500 3175);
DISPLAY INVISIBLE (-1500 3175);
FORCEPROP 2 LAST CDS_LOCATION C1T56
J 0
(-1500 3125);
DISPLAY 0.617021 (-1500 3125);
PAINT AQUA (-1500 3125);
DISPLAY INVISIBLE (-1500 3125);
FORCEPROP 2 LAST CDS_LIB dev_discrete
J 0
(-1550 3025);
PAINT ORANGE (-1550 3025);
DISPLAY INVISIBLE (-1550 3025);
FORCEADD GND..1
(-1550 2725);
FORCEPROP 3 LASTPIN (-1550 2775) SIG_NAME GND\g
J 0
(-1540 2785);
DISPLAY 0.659574 (-1540 2785);
PAINT MONO (-1540 2785);
DISPLAY INVISIBLE (-1540 2785);
FORCEPROP 1 LAST PATH I185
J 0
(-1475 2725);
DISPLAY 0.872340 (-1475 2725);
PAINT AQUA (-1475 2725);
DISPLAY INVISIBLE (-1475 2725);
FORCEPROP 1 LAST SIZE 1B
J 0
(-1475 2675);
DISPLAY 0.872340 (-1475 2675);
PAINT AQUA (-1475 2675);
DISPLAY INVISIBLE (-1475 2675);
FORCEPROP 1 LAST HDL_POWER GND
J 0
(-1550 2875);
DISPLAY 0.872340 (-1550 2875);
PAINT GREEN (-1550 2875);
DISPLAY INVISIBLE (-1550 2875);
FORCEPROP 1 LAST BODY_TYPE PLUMBING
J 0
(-1595 2682);
DISPLAY 0.340426 (-1595 2682);
PAINT GREEN (-1595 2682);
DISPLAY INVISIBLE (-1595 2682);
FORCEPROP 2 LAST CDS_LIB mstr_symbols
J 0
(-1550 2725);
PAINT ORANGE (-1550 2725);
DISPLAY INVISIBLE (-1550 2725);
FORCEPROP 1 LAST VOLTAGE 0.0V
J 0
(-1595 2682);
DISPLAY 0.340426 (-1595 2682);
PAINT SKYBLUE (-1595 2682);
DISPLAY INVISIBLE (-1595 2682);
FORCEADD RES..1
(-7050 2000);
FORCEPROP 1 LASTPIN (-6950 2000) $PN 2
J 0
(-6988 2012);
DISPLAY 0.617021 (-6988 2012);
PAINT ORANGE (-6988 2012);
FORCEPROP 1 LAST LOCATION R1L2
J 0
(-7100 2050);
DISPLAY 0.617021 (-7100 2050);
PAINT AQUA (-7100 2050);
FORCEPROP 1 LASTPIN (-7150 2000) $PN 1
J 0
(-7138 2012);
DISPLAY 0.617021 (-7138 2012);
PAINT ORANGE (-7138 2012);
FORCEPROP 1 LAST PART_NUMBER G21796-066
J 0
(-7150 1900);
DISPLAY 0.617021 (-7150 1900);
PAINT BLUE (-7150 1900);
FORCEPROP 1 LAST WATTAGE 1/16W
J 2
(-7175 1950);
DISPLAY 0.617021 (-7175 1950);
PAINT SKYBLUE (-7175 1950);
FORCEPROP 1 LAST VALUE 10.0
J 2
(-7075 1950);
DISPLAY 0.617021 (-7075 1950);
PAINT SKYBLUE (-7075 1950);
FORCEPROP 1 LAST TOLERANCE 1%
J 0
(-7000 1950);
DISPLAY 0.617021 (-7000 1950);
PAINT SKYBLUE (-7000 1950);
FORCEPROP 1 LAST PACK_TYPE 0402
J 0
(-6900 1950);
DISPLAY 0.617021 (-6900 1950);
PAINT SKYBLUE (-6900 1950);
FORCEPROP 1 LAST MATERIAL CHIP
J 0
(-6750 1950);
DISPLAY 0.638298 (-6750 1950);
PAINT SKYBLUE (-6750 1950);
FORCEPROP 2 LAST CDS_LIB mstr_discrete
J 0
(-7050 2000);
PAINT ORANGE (-7050 2000);
DISPLAY INVISIBLE (-7050 2000);
FORCEPROP 2 LAST BOM_COST DEBUG
J 0
(-7100 2150);
DISPLAY 1.021277 (-7100 2150);
PAINT ORANGE (-7100 2150);
DISPLAY INVISIBLE (-7100 2150);
FORCEPROP 2 LAST CDS_SEC 1
J 0
(-7100 2200);
PAINT MONO (-7100 2200);
DISPLAY INVISIBLE (-7100 2200);
FORCEPROP 2 LAST ROOM BMC_DEBUG_HEADER
J 0
(-7100 2100);
DISPLAY 1.021277 (-7100 2100);
PAINT ORANGE (-7100 2100);
DISPLAY INVISIBLE (-7100 2100);
FORCEPROP 1 LAST PATH I186
J 0
(-7100 2150);
DISPLAY 0.978723 (-7100 2150);
PAINT WHITE (-7100 2150);
DISPLAY INVISIBLE (-7100 2150);
FORCEPROP 2 LAST CDS_LOCATION R1L2
J 0
(-7100 2050);
DISPLAY 0.617021 (-7100 2050);
PAINT AQUA (-7100 2050);
DISPLAY INVISIBLE (-7100 2050);
FORCEPROP 2 LAST $SEC 1
J 0
(-7100 2200);
PAINT MONO (-7100 2200);
DISPLAY INVISIBLE (-7100 2200);
FORCEADD FET_N_DUAL..5
(-5950 2100);
FORCEPROP 1 LAST PART_NUMBER E40049-001
J 0
(-5750 1900);
DISPLAY 0.617021 (-5750 1900);
PAINT BLUE (-5750 1900);
FORCEPROP 1 LASTPIN (-6150 2000) $PN 5
J 2
(-6147 2015);
DISPLAY 0.617021 (-6147 2015);
PAINT WHITE (-6147 2015);
FORCEPROP 1 LASTPIN (-5950 2300) $PN 3
J 2
(-5897 2265);
DISPLAY 0.617021 (-5897 2265);
PAINT WHITE (-5897 2265);
FORCEPROP 1 LASTPIN (-5950 1900) $PN 4
J 2
(-5892 1900);
DISPLAY 0.617021 (-5892 1900);
PAINT WHITE (-5892 1900);
FORCEPROP 1 LAST MATERIAL FET
J 0
(-5750 2000);
DISPLAY 0.617021 (-5750 2000);
PAINT SKYBLUE (-5750 2000);
FORCEPROP 1 LAST VALUE NTJD4001N
J 0
(-5750 2050);
DISPLAY 0.617021 (-5750 2050);
PAINT SKYBLUE (-5750 2050);
FORCEPROP 1 LAST LOCATION Q1L2
J 0
(-5750 2100);
DISPLAY 0.617021 (-5750 2100);
PAINT AQUA (-5750 2100);
FORCEPROP 1 LAST PACK_TYPE SMLF
J 0
(-5750 1950);
DISPLAY 0.978723 (-5750 1950);
PAINT SKYBLUE (-5750 1950);
DISPLAY INVISIBLE (-5750 1950);
FORCEPROP 2 LAST CDS_LIB mstr_discrete
J 0
(-5950 2100);
PAINT ORANGE (-5950 2100);
DISPLAY INVISIBLE (-5950 2100);
FORCEPROP 0 LAST ROOM BMC
J 0
(-5750 2200);
DISPLAY 1.021277 (-5750 2200);
PAINT ORANGE (-5750 2200);
DISPLAY INVISIBLE (-5750 2200);
FORCEPROP 1 LAST PATH I187
J 0
(-5750 2150);
DISPLAY 0.978723 (-5750 2150);
PAINT BLUE (-5750 2150);
DISPLAY INVISIBLE (-5750 2150);
FORCEPROP 2 LAST CDS_LOCATION Q1L2
J 0
(-5750 2100);
DISPLAY 0.617021 (-5750 2100);
PAINT AQUA (-5750 2100);
DISPLAY INVISIBLE (-5750 2100);
FORCEPROP 2 LAST SEC 2
J 0
(-5750 2200);
DISPLAY 0.680851 (-5750 2200);
PAINT MONO (-5750 2200);
DISPLAY INVISIBLE (-5750 2200);
FORCEPROP 0 LAST BOM_COST BMC_DEBUG_HEADER
J 0
(-5750 2300);
DISPLAY 1.021277 (-5750 2300);
PAINT ORANGE (-5750 2300);
DISPLAY INVISIBLE (-5750 2300);
FORCEPROP 2 LAST SEC_TYPE SMLF
J 0
(-5750 2200);
DISPLAY 1.021277 (-5750 2200);
PAINT ORANGE (-5750 2200);
DISPLAY INVISIBLE (-5750 2200);
FORCEADD FET_N_DUAL..5
R 1
(-4950 2625);
FORCEPROP 1 LASTPIN (-4750 2625) $PN 1
R 1
J 2
(-4750 2683);
DISPLAY 0.617021 (-4750 2683);
PAINT WHITE (-4750 2683);
FORCEPROP 1 LAST LOCATION Q1L2
J 0
(-4725 2475);
DISPLAY 0.617021 (-4725 2475);
PAINT AQUA (-4725 2475);
FORCEPROP 1 LASTPIN (-5150 2625) $PN 6
R 1
J 2
(-5115 2678);
DISPLAY 0.617021 (-5115 2678);
PAINT WHITE (-5115 2678);
FORCEPROP 1 LAST PART_NUMBER E40049-001
J 0
(-4725 2300);
DISPLAY 0.617021 (-4725 2300);
PAINT BLUE (-4725 2300);
FORCEPROP 1 LASTPIN (-4850 2425) $PN 2
R 1
J 2
(-4865 2428);
DISPLAY 0.617021 (-4865 2428);
PAINT WHITE (-4865 2428);
FORCEPROP 1 LAST MATERIAL FET
J 0
(-4725 2375);
DISPLAY 0.617021 (-4725 2375);
PAINT SKYBLUE (-4725 2375);
FORCEPROP 1 LAST VALUE NTJD4001N
J 0
(-4725 2425);
DISPLAY 0.617021 (-4725 2425);
PAINT SKYBLUE (-4725 2425);
FORCEPROP 0 LAST BOM_COST BMC_DEBUG_HEADER
R 1
J 0
(-4750 2625);
DISPLAY 1.021277 (-4750 2625);
PAINT ORANGE (-4750 2625);
DISPLAY INVISIBLE (-4750 2625);
FORCEPROP 0 LAST ROOM BMC
R 1
J 0
(-4725 2575);
DISPLAY 1.021277 (-4725 2575);
PAINT ORANGE (-4725 2575);
DISPLAY INVISIBLE (-4725 2575);
FORCEPROP 1 LAST PACK_TYPE SMLF
R 1
J 0
(-4800 2825);
DISPLAY 0.978723 (-4800 2825);
PAINT SKYBLUE (-4800 2825);
DISPLAY INVISIBLE (-4800 2825);
FORCEPROP 1 LAST PATH I188
R 1
J 0
(-5000 2825);
DISPLAY 0.978723 (-5000 2825);
PAINT BLUE (-5000 2825);
DISPLAY INVISIBLE (-5000 2825);
FORCEPROP 2 LAST CDS_LIB mstr_discrete
R 1
J 0
(-4950 2625);
PAINT ORANGE (-4950 2625);
DISPLAY INVISIBLE (-4950 2625);
FORCEPROP 2 LAST SEC_TYPE SMLF
R 1
J 0
(-5050 2825);
DISPLAY 1.021277 (-5050 2825);
PAINT ORANGE (-5050 2825);
DISPLAY INVISIBLE (-5050 2825);
FORCEPROP 2 LAST SEC 1
R 1
J 0
(-5050 2825);
DISPLAY 0.680851 (-5050 2825);
PAINT MONO (-5050 2825);
DISPLAY INVISIBLE (-5050 2825);
FORCEPROP 2 LAST CDS_LOCATION Q1L2
J 0
(-4725 2475);
DISPLAY 0.617021 (-4725 2475);
PAINT AQUA (-4725 2475);
DISPLAY INVISIBLE (-4725 2475);
FORCEADD P12V_STBY..1
(-5950 2900);
FORCEPROP 3 LASTPIN (-5950 2850) SIG_NAME P12V_STBY\g
J 0
(-5940 2860);
DISPLAY 0.659574 (-5940 2860);
PAINT MONO (-5940 2860);
DISPLAY INVISIBLE (-5940 2860);
FORCEPROP 2 LAST CDS_LIB mstr_symbols
J 0
(-5950 2900);
PAINT ORANGE (-5950 2900);
DISPLAY INVISIBLE (-5950 2900);
FORCEPROP 1 LAST PATH I193
J 0
(-5905 2902);
DISPLAY 0.340426 (-5905 2902);
PAINT GREEN (-5905 2902);
DISPLAY INVISIBLE (-5905 2902);
FORCEPROP 1 LAST HDL_POWER P12V_STBY
J 0
(-6250 2775);
DISPLAY 0.872340 (-6250 2775);
PAINT ORANGE (-6250 2775);
DISPLAY INVISIBLE (-6250 2775);
FORCEPROP 1 LAST BODY_TYPE PLUMBING
J 0
(-5995 2857);
DISPLAY 0.340426 (-5995 2857);
PAINT GREEN (-5995 2857);
DISPLAY INVISIBLE (-5995 2857);
FORCEPROP 1 LAST SIZE 1B
J 0
(-5905 2922);
DISPLAY 0.340426 (-5905 2922);
PAINT GREEN (-5905 2922);
DISPLAY INVISIBLE (-5905 2922);
FORCEPROP 1 LAST VOLTAGE 12.0V
J 0
(-5995 2857);
DISPLAY 0.340426 (-5995 2857);
PAINT SKYBLUE (-5995 2857);
DISPLAY INVISIBLE (-5995 2857);
FORCEADD P5V_STBY..1
(-3350 1250);
FORCEPROP 3 LASTPIN (-3350 1200) SIG_NAME P5V_STBY\g
J 0
(-3340 1210);
DISPLAY 0.659574 (-3340 1210);
PAINT MONO (-3340 1210);
DISPLAY INVISIBLE (-3340 1210);
FORCEPROP 1 LAST HDL_POWER P5V_STBY
J 0
(-3650 1125);
DISPLAY 0.872340 (-3650 1125);
PAINT ORANGE (-3650 1125);
DISPLAY INVISIBLE (-3650 1125);
FORCEPROP 1 LAST PATH I194
J 0
(-3305 1252);
DISPLAY 0.340426 (-3305 1252);
PAINT GREEN (-3305 1252);
DISPLAY INVISIBLE (-3305 1252);
FORCEPROP 1 LAST BODY_TYPE PLUMBING
J 0
(-3395 1207);
DISPLAY 0.340426 (-3395 1207);
PAINT GREEN (-3395 1207);
DISPLAY INVISIBLE (-3395 1207);
FORCEPROP 1 LAST SIZE 1B
J 0
(-3305 1272);
DISPLAY 0.340426 (-3305 1272);
PAINT GREEN (-3305 1272);
DISPLAY INVISIBLE (-3305 1272);
FORCEPROP 2 LAST CDS_LIB mstr_symbols
J 0
(-3350 1250);
PAINT ORANGE (-3350 1250);
DISPLAY INVISIBLE (-3350 1250);
FORCEPROP 1 LAST VOLTAGE 5.0V
J 0
(-3395 1207);
DISPLAY 0.340426 (-3395 1207);
PAINT SKYBLUE (-3395 1207);
DISPLAY INVISIBLE (-3395 1207);
FORCEADD RES..1
(-1950 1775);
FORCEPROP 1 LAST VALUE 0.0
J 2
(-1975 1725);
DISPLAY 0.617021 (-1975 1725);
PAINT SKYBLUE (-1975 1725);
FORCEPROP 1 LAST MATERIAL CHIP
J 0
(-1950 1675);
DISPLAY 0.617021 (-1950 1675);
PAINT SKYBLUE (-1950 1675);
FORCEPROP 1 LAST TOLERANCE 5%
J 0
(-1950 1725);
DISPLAY 0.617021 (-1950 1725);
PAINT SKYBLUE (-1950 1725);
FORCEPROP 0 LAST POP NOPOP
J 0
(-2025 1925);
DISPLAY 1.021277 (-2025 1925);
PAINT RED (-2025 1925);
FORCEPROP 1 LAST PART_NUMBER G21497-005
J 0
(-2000 1875);
DISPLAY 0.617021 (-2000 1875);
PAINT BLUE (-2000 1875);
FORCEPROP 1 LAST LOCATION R6W19
J 0
(-2000 1825);
DISPLAY 0.617021 (-2000 1825);
PAINT AQUA (-2000 1825);
FORCEPROP 1 LASTPIN (-1850 1775) $PN 2
J 0
(-1888 1787);
DISPLAY 0.787234 (-1888 1787);
PAINT ORANGE (-1888 1787);
FORCEPROP 1 LASTPIN (-2050 1775) $PN 1
J 0
(-2038 1787);
DISPLAY 0.787234 (-2038 1787);
PAINT ORANGE (-2038 1787);
FORCEPROP 1 LAST PACK_TYPE 0402
J 0
(-1700 1675);
DISPLAY 0.617021 (-1700 1675);
PAINT SKYBLUE (-1700 1675);
FORCEPROP 1 LAST WATTAGE 1/16W
J 2
(-1975 1675);
DISPLAY 0.617021 (-1975 1675);
PAINT SKYBLUE (-1975 1675);
FORCEPROP 2 LAST CDS_LIB mstr_discrete
J 0
(-1950 1775);
PAINT MONO (-1950 1775);
DISPLAY INVISIBLE (-1950 1775);
FORCEPROP 1 LAST PATH I196
J 0
(-2000 1925);
DISPLAY 0.978723 (-2000 1925);
PAINT WHITE (-2000 1925);
DISPLAY INVISIBLE (-2000 1925);
FORCEPROP 2 LAST ROOM BMC_DEBUG_HEADER
J 0
(-2000 1925);
DISPLAY 1.021277 (-2000 1925);
PAINT ORANGE (-2000 1925);
DISPLAY INVISIBLE (-2000 1925);
FORCEPROP 2 LAST BOM_COST DEBUG
J 0
(-2000 1975);
DISPLAY 1.021277 (-2000 1975);
PAINT ORANGE (-2000 1975);
DISPLAY INVISIBLE (-2000 1975);
FORCEPROP 0 LAST SEC 1
J 0
(-2025 1975);
DISPLAY 0.680851 (-2025 1975);
PAINT MONO (-2025 1975);
DISPLAY INVISIBLE (-2025 1975);
FORCEPROP 2 LAST SEC_TYPE 0402
J 0
(-2000 1975);
DISPLAY 1.021277 (-2000 1975);
PAINT ORANGE (-2000 1975);
DISPLAY INVISIBLE (-2000 1975);
FORCEADD P5V_STBY..1
(-5400 2750);
FORCEPROP 3 LASTPIN (-5400 2700) SIG_NAME P5V_STBY\g
J 0
(-5390 2710);
DISPLAY 0.659574 (-5390 2710);
PAINT MONO (-5390 2710);
DISPLAY INVISIBLE (-5390 2710);
FORCEPROP 1 LAST PATH I197
J 0
(-5355 2752);
DISPLAY 0.340426 (-5355 2752);
PAINT GREEN (-5355 2752);
DISPLAY INVISIBLE (-5355 2752);
FORCEPROP 1 LAST SIZE 1B
J 0
(-5355 2772);
DISPLAY 0.340426 (-5355 2772);
PAINT GREEN (-5355 2772);
DISPLAY INVISIBLE (-5355 2772);
FORCEPROP 1 LAST VOLTAGE 5.0V
J 0
(-5445 2707);
DISPLAY 0.340426 (-5445 2707);
PAINT SKYBLUE (-5445 2707);
DISPLAY INVISIBLE (-5445 2707);
FORCEPROP 1 LAST BODY_TYPE PLUMBING
J 0
(-5445 2707);
DISPLAY 0.340426 (-5445 2707);
PAINT GREEN (-5445 2707);
DISPLAY INVISIBLE (-5445 2707);
FORCEPROP 1 LAST HDL_POWER P5V_STBY
J 0
(-5700 2625);
DISPLAY 0.872340 (-5700 2625);
PAINT ORANGE (-5700 2625);
DISPLAY INVISIBLE (-5700 2625);
FORCEPROP 2 LAST CDS_LIB mstr_symbols
J 0
(-5400 2750);
PAINT ORANGE (-5400 2750);
DISPLAY INVISIBLE (-5400 2750);
FORCEADD RES..2
(-3350 1050);
FORCEPROP 1 LAST TOLERANCE 1%
J 0
(-3305 1075);
DISPLAY 0.617021 (-3305 1075);
PAINT SKYBLUE (-3305 1075);
FORCEPROP 1 LASTPIN (-3350 1150) $PN 1
J 0
(-3345 1112);
DISPLAY 0.617021 (-3345 1112);
PAINT ORANGE (-3345 1112);
FORCEPROP 1 LAST VALUE 20.0K
J 0
(-3305 1125);
DISPLAY 0.617021 (-3305 1125);
PAINT SKYBLUE (-3305 1125);
FORCEPROP 1 LAST PART_NUMBER G21796-040
J 0
(-3310 925);
DISPLAY 0.617021 (-3310 925);
PAINT BLUE (-3310 925);
FORCEPROP 1 LAST WATTAGE 1/16W
J 0
(-3310 1025);
DISPLAY 0.617021 (-3310 1025);
PAINT SKYBLUE (-3310 1025);
FORCEPROP 1 LAST MATERIAL CHIP
J 0
(-3310 975);
DISPLAY 0.617021 (-3310 975);
PAINT SKYBLUE (-3310 975);
FORCEPROP 1 LAST PACK_TYPE 0402
J 0
(-3310 875);
DISPLAY 0.617021 (-3310 875);
PAINT SKYBLUE (-3310 875);
FORCEPROP 1 LAST LOCATION R9A5
J 0
(-3305 1175);
DISPLAY 0.617021 (-3305 1175);
PAINT AQUA (-3305 1175);
FORCEPROP 1 LASTPIN (-3350 950) $PN 2
J 0
(-3345 960);
DISPLAY 0.617021 (-3345 960);
PAINT ORANGE (-3345 960);
FORCEPROP 2 LAST CDS_LOCATION R9A5
J 0
(-3305 1175);
DISPLAY 0.617021 (-3305 1175);
PAINT AQUA (-3305 1175);
DISPLAY INVISIBLE (-3305 1175);
FORCEPROP 1 LAST PATH I198
J 0
(-3300 1225);
DISPLAY 0.978723 (-3300 1225);
PAINT WHITE (-3300 1225);
DISPLAY INVISIBLE (-3300 1225);
FORCEPROP 2 LAST ROOM SB
J 0
(-3305 1125);
DISPLAY 1.361702 (-3305 1125);
PAINT ORANGE (-3305 1125);
DISPLAY INVISIBLE (-3305 1125);
FORCEPROP 2 LAST BOM_COST SB
R 3
J 0
(-3175 1000);
PAINT ORANGE (-3175 1000);
DISPLAY INVISIBLE (-3175 1000);
FORCEPROP 2 LAST CDS_LIB mstr_discrete
J 0
(-3350 1050);
PAINT ORANGE (-3350 1050);
DISPLAY INVISIBLE (-3350 1050);
FORCEPROP 2 LAST SEC_TYPE 0402
J 0
(-3300 1275);
DISPLAY 1.021277 (-3300 1275);
PAINT ORANGE (-3300 1275);
DISPLAY INVISIBLE (-3300 1275);
FORCEPROP 2 LAST SEC 1
J 0
(-3300 1275);
DISPLAY 0.680851 (-3300 1275);
PAINT MONO (-3300 1275);
DISPLAY INVISIBLE (-3300 1275);
FORCEADD P3V3_STBY..1
(-2700 1950);
FORCEPROP 3 LASTPIN (-2700 1900) SIG_NAME P3V3_STBY\g
J 0
(-2690 1910);
DISPLAY 0.659574 (-2690 1910);
PAINT MONO (-2690 1910);
DISPLAY INVISIBLE (-2690 1910);
FORCEPROP 1 LAST HDL_POWER P3V3_STBY
J 0
(-3000 1825);
DISPLAY 0.872340 (-3000 1825);
PAINT ORANGE (-3000 1825);
DISPLAY INVISIBLE (-3000 1825);
FORCEPROP 1 LAST VOLTAGE 3.3V
J 0
(-2745 1907);
DISPLAY 0.340426 (-2745 1907);
PAINT SKYBLUE (-2745 1907);
DISPLAY INVISIBLE (-2745 1907);
FORCEPROP 2 LAST CDS_LIB mstr_symbols
J 0
(-2700 1950);
PAINT ORANGE (-2700 1950);
DISPLAY INVISIBLE (-2700 1950);
FORCEPROP 1 LAST BODY_TYPE PLUMBING
J 0
(-2745 1907);
DISPLAY 0.340426 (-2745 1907);
PAINT GREEN (-2745 1907);
DISPLAY INVISIBLE (-2745 1907);
FORCEPROP 1 LAST SIZE 1B
J 0
(-2655 1972);
DISPLAY 0.340426 (-2655 1972);
PAINT GREEN (-2655 1972);
DISPLAY INVISIBLE (-2655 1972);
FORCEPROP 1 LAST PATH I199
J 0
(-2655 1952);
DISPLAY 0.340426 (-2655 1952);
PAINT GREEN (-2655 1952);
DISPLAY INVISIBLE (-2655 1952);
FORCEADD RES..2
(-2700 1700);
FORCEPROP 1 LASTPIN (-2700 1800) $PN 1
J 0
(-2695 1762);
DISPLAY 0.617021 (-2695 1762);
PAINT ORANGE (-2695 1762);
FORCEPROP 1 LAST TOLERANCE 1%
J 0
(-2655 1725);
DISPLAY 0.617021 (-2655 1725);
PAINT SKYBLUE (-2655 1725);
FORCEPROP 1 LAST LOCATION R6W40
J 0
(-2655 1825);
DISPLAY 0.617021 (-2655 1825);
PAINT AQUA (-2655 1825);
FORCEPROP 1 LAST VALUE 10.0K
J 0
(-2655 1775);
DISPLAY 0.617021 (-2655 1775);
PAINT SKYBLUE (-2655 1775);
FORCEPROP 1 LAST WATTAGE 1/16W
J 0
(-2660 1675);
DISPLAY 0.617021 (-2660 1675);
PAINT SKYBLUE (-2660 1675);
FORCEPROP 1 LAST MATERIAL CHIP
J 0
(-2660 1625);
DISPLAY 0.617021 (-2660 1625);
PAINT SKYBLUE (-2660 1625);
FORCEPROP 1 LAST PART_NUMBER G21796-016
J 0
(-2660 1575);
DISPLAY 0.617021 (-2660 1575);
PAINT BLUE (-2660 1575);
FORCEPROP 1 LASTPIN (-2700 1600) $PN 2
J 0
(-2695 1610);
DISPLAY 0.617021 (-2695 1610);
PAINT ORANGE (-2695 1610);
FORCEPROP 1 LAST PACK_TYPE 0402
J 0
(-2660 1525);
DISPLAY 0.617021 (-2660 1525);
PAINT SKYBLUE (-2660 1525);
FORCEPROP 2 LAST CDS_LOCATION R6W40
J 0
(-2655 1825);
DISPLAY 0.617021 (-2655 1825);
PAINT AQUA (-2655 1825);
DISPLAY INVISIBLE (-2655 1825);
FORCEPROP 1 LAST PATH I201
J 0
(-2650 1875);
DISPLAY 0.978723 (-2650 1875);
PAINT WHITE (-2650 1875);
DISPLAY INVISIBLE (-2650 1875);
FORCEPROP 2 LAST ROOM CPU0
J 0
(-2675 1475);
PAINT WHITE (-2675 1475);
DISPLAY INVISIBLE (-2675 1475);
FORCEPROP 2 LAST BOM_COST PROC_SIDEBAND
J 0
(-2700 1700);
PAINT WHITE (-2700 1700);
DISPLAY INVISIBLE (-2700 1700);
FORCEPROP 2 LAST CDS_LIB mstr_discrete
J 2
(-2700 1700);
PAINT ORANGE (-2700 1700);
DISPLAY INVISIBLE (-2700 1700);
FORCEPROP 2 LAST SEC_TYPE 0402
J 0
(-2650 1925);
DISPLAY 1.021277 (-2650 1925);
PAINT ORANGE (-2650 1925);
DISPLAY INVISIBLE (-2650 1925);
FORCEPROP 2 LAST SEC 1
J 0
(-2650 1925);
DISPLAY 0.680851 (-2650 1925);
PAINT MONO (-2650 1925);
DISPLAY INVISIBLE (-2650 1925);
FORCEADD DIODE..3
(-2900 1400);
FORCEPROP 1 LAST MATERIAL IC
J 0
(-3000 1522);
DISPLAY 0.617021 (-3000 1522);
PAINT SKYBLUE (-3000 1522);
FORCEPROP 1 LAST PACK_TYPE SMLF
J 0
(-3000 1460);
DISPLAY 0.617021 (-3000 1460);
PAINT SKYBLUE (-3000 1460);
FORCEPROP 1 LAST LOCATION CR9W1
J 0
(-3002 1681);
DISPLAY 0.617021 (-3002 1681);
PAINT AQUA (-3002 1681);
FORCEPROP 1 LAST VALUE BAT54WS
J 0
(-3000 1575);
DISPLAY 0.617021 (-3000 1575);
PAINT SKYBLUE (-3000 1575);
FORCEPROP 1 LASTPIN (-2800 1400) $PN 2
J 0
(-2825 1410);
DISPLAY 0.617021 (-2825 1410);
PAINT AQUA (-2825 1410);
FORCEPROP 1 LASTPIN (-3000 1400) $PN 1
J 2
(-2965 1410);
DISPLAY 0.617021 (-2965 1410);
PAINT AQUA (-2965 1410);
FORCEPROP 1 LAST PART_NUMBER C73510-001
J 0
(-3000 1625);
DISPLAY 0.617021 (-3000 1625);
PAINT BLUE (-3000 1625);
FORCEPROP 1 LAST PATH I202
J 0
(-2920 1610);
DISPLAY 0.978723 (-2920 1610);
PAINT PINK (-2920 1610);
DISPLAY INVISIBLE (-2920 1610);
FORCEPROP 2 LAST SEC 1
J 0
(-2900 1675);
PAINT MONO (-2900 1675);
DISPLAY INVISIBLE (-2900 1675);
FORCEPROP 2 LAST SEC_TYPE SMLF
J 0
(-2900 1675);
DISPLAY 1.021277 (-2900 1675);
PAINT ORANGE (-2900 1675);
DISPLAY INVISIBLE (-2900 1675);
FORCEPROP 2 LAST CDS_LIB mstr_discrete
J 0
(-2900 1400);
PAINT ORANGE (-2900 1400);
DISPLAY INVISIBLE (-2900 1400);
FORCEADD OFFPAGE..4
(-3600 1600);
FORCEPROP 2 LAST $XR1 247 
J 0
(-3294 1600);
DISPLAY 0.638298 (-3294 1600);
PAINT MONO (-3294 1600);
FORCEPROP 2 LAST $XR0 155 
J 0
(-3414 1600);
DISPLAY 0.638298 (-3414 1600);
PAINT MONO (-3414 1600);
FORCEPROP 1 LAST OFFPAGE TRUE
J 0
(-3275 1475);
DISPLAY 0.872340 (-3275 1475);
PAINT GREEN (-3275 1475);
DISPLAY INVISIBLE (-3275 1475);
FORCEPROP 1 LAST COMMENT_BODY TRUE
J 0
(-3625 1500);
DISPLAY 0.872340 (-3625 1500);
PAINT GREEN (-3625 1500);
DISPLAY INVISIBLE (-3625 1500);
FORCEPROP 2 LAST CDS_LIB mstr_standard
J 0
(-3600 1600);
PAINT ORANGE (-3600 1600);
DISPLAY INVISIBLE (-3600 1600);
FORCEPROP 2 LAST PATH I31
J 0
(-3375 1650);
DISPLAY 1.021277 (-3375 1650);
PAINT ORANGE (-3375 1650);
DISPLAY INVISIBLE (-3375 1650);
FORCEADD OFFPAGE..4
(-3600 1550);
FORCEPROP 2 LAST $XR1 247 
J 0
(-3294 1550);
DISPLAY 0.638298 (-3294 1550);
PAINT MONO (-3294 1550);
FORCEPROP 2 LAST $XR0 155 
J 0
(-3414 1550);
DISPLAY 0.638298 (-3414 1550);
PAINT MONO (-3414 1550);
FORCEPROP 1 LAST COMMENT_BODY TRUE
J 0
(-3625 1450);
DISPLAY 0.872340 (-3625 1450);
PAINT GREEN (-3625 1450);
DISPLAY INVISIBLE (-3625 1450);
FORCEPROP 1 LAST OFFPAGE TRUE
J 0
(-3275 1425);
DISPLAY 0.872340 (-3275 1425);
PAINT GREEN (-3275 1425);
DISPLAY INVISIBLE (-3275 1425);
FORCEPROP 2 LAST CDS_LIB mstr_standard
J 0
(-3600 1550);
PAINT ORANGE (-3600 1550);
DISPLAY INVISIBLE (-3600 1550);
FORCEPROP 2 LAST PATH I32
J 0
(-3375 1600);
DISPLAY 1.021277 (-3375 1600);
PAINT ORANGE (-3375 1600);
DISPLAY INVISIBLE (-3375 1600);
FORCEADD OFFPAGE..4
(-3600 1500);
FORCEPROP 2 LAST $XR1 247 
J 0
(-3294 1500);
DISPLAY 0.638298 (-3294 1500);
PAINT MONO (-3294 1500);
FORCEPROP 2 LAST $XR0 155 
J 0
(-3414 1500);
DISPLAY 0.638298 (-3414 1500);
PAINT MONO (-3414 1500);
FORCEPROP 1 LAST COMMENT_BODY TRUE
J 0
(-3625 1400);
DISPLAY 0.872340 (-3625 1400);
PAINT GREEN (-3625 1400);
DISPLAY INVISIBLE (-3625 1400);
FORCEPROP 1 LAST OFFPAGE TRUE
J 0
(-3275 1375);
DISPLAY 0.872340 (-3275 1375);
PAINT GREEN (-3275 1375);
DISPLAY INVISIBLE (-3275 1375);
FORCEPROP 2 LAST CDS_LIB mstr_standard
J 0
(-3600 1500);
PAINT ORANGE (-3600 1500);
DISPLAY INVISIBLE (-3600 1500);
FORCEPROP 2 LAST PATH I33
J 0
(-3375 1550);
DISPLAY 1.021277 (-3375 1550);
PAINT ORANGE (-3375 1550);
DISPLAY INVISIBLE (-3375 1550);
FORCEADD OFFPAGE..4
(-3600 1450);
FORCEPROP 2 LAST $XR1 247 
J 0
(-3294 1450);
DISPLAY 0.638298 (-3294 1450);
PAINT MONO (-3294 1450);
FORCEPROP 2 LAST $XR0 155 
J 0
(-3414 1450);
DISPLAY 0.638298 (-3414 1450);
PAINT MONO (-3414 1450);
FORCEPROP 1 LAST COMMENT_BODY TRUE
J 0
(-3625 1350);
DISPLAY 0.872340 (-3625 1350);
PAINT GREEN (-3625 1350);
DISPLAY INVISIBLE (-3625 1350);
FORCEPROP 2 LAST CDS_LIB mstr_standard
J 0
(-3600 1450);
PAINT ORANGE (-3600 1450);
DISPLAY INVISIBLE (-3600 1450);
FORCEPROP 1 LAST OFFPAGE TRUE
J 0
(-3275 1325);
DISPLAY 0.872340 (-3275 1325);
PAINT GREEN (-3275 1325);
DISPLAY INVISIBLE (-3275 1325);
FORCEPROP 2 LAST PATH I34
J 0
(-3375 1500);
DISPLAY 1.021277 (-3375 1500);
PAINT ORANGE (-3375 1500);
DISPLAY INVISIBLE (-3375 1500);
FORCEADD OFFPAGE..1
(-5450 1600);
FORCEPROP 2 LAST $XR1 247 
J 0
(-5852 1600);
DISPLAY 0.638298 (-5852 1600);
PAINT MONO (-5852 1600);
FORCEPROP 2 LAST $XR0 155 
J 0
(-5732 1600);
DISPLAY 0.638298 (-5732 1600);
PAINT MONO (-5732 1600);
FORCEPROP 1 LAST OFFPAGE TRUE
J 0
(-5125 1475);
DISPLAY 0.872340 (-5125 1475);
PAINT GREEN (-5125 1475);
DISPLAY INVISIBLE (-5125 1475);
FORCEPROP 1 LAST COMMENT_BODY TRUE
J 0
(-5325 1500);
DISPLAY 0.872340 (-5325 1500);
PAINT GREEN (-5325 1500);
DISPLAY INVISIBLE (-5325 1500);
FORCEPROP 2 LAST PATH I37
J 0
(-5900 1650);
DISPLAY 1.021277 (-5900 1650);
PAINT ORANGE (-5900 1650);
DISPLAY INVISIBLE (-5900 1650);
FORCEPROP 2 LAST CDS_LIB mstr_standard
J 0
(-5450 1600);
PAINT ORANGE (-5450 1600);
DISPLAY INVISIBLE (-5450 1600);
FORCEADD OFFPAGE..1
(-5450 1550);
FORCEPROP 2 LAST $XR1 247 
J 0
(-5852 1550);
DISPLAY 0.638298 (-5852 1550);
PAINT MONO (-5852 1550);
FORCEPROP 2 LAST $XR0 155 
J 0
(-5732 1550);
DISPLAY 0.638298 (-5732 1550);
PAINT MONO (-5732 1550);
FORCEPROP 1 LAST COMMENT_BODY TRUE
J 0
(-5325 1450);
DISPLAY 0.872340 (-5325 1450);
PAINT GREEN (-5325 1450);
DISPLAY INVISIBLE (-5325 1450);
FORCEPROP 1 LAST OFFPAGE TRUE
J 0
(-5125 1425);
DISPLAY 0.872340 (-5125 1425);
PAINT GREEN (-5125 1425);
DISPLAY INVISIBLE (-5125 1425);
FORCEPROP 2 LAST PATH I38
J 0
(-5725 1600);
DISPLAY 1.021277 (-5725 1600);
PAINT ORANGE (-5725 1600);
DISPLAY INVISIBLE (-5725 1600);
FORCEPROP 2 LAST CDS_LIB mstr_standard
J 0
(-5450 1550);
PAINT ORANGE (-5450 1550);
DISPLAY INVISIBLE (-5450 1550);
FORCEADD OFFPAGE..1
(-5450 1500);
FORCEPROP 2 LAST $XR1 247 
J 0
(-5852 1500);
DISPLAY 0.638298 (-5852 1500);
PAINT MONO (-5852 1500);
FORCEPROP 2 LAST $XR0 155 
J 0
(-5732 1500);
DISPLAY 0.638298 (-5732 1500);
PAINT MONO (-5732 1500);
FORCEPROP 1 LAST COMMENT_BODY TRUE
J 0
(-5325 1400);
DISPLAY 0.872340 (-5325 1400);
PAINT GREEN (-5325 1400);
DISPLAY INVISIBLE (-5325 1400);
FORCEPROP 1 LAST OFFPAGE TRUE
J 0
(-5125 1375);
DISPLAY 0.872340 (-5125 1375);
PAINT GREEN (-5125 1375);
DISPLAY INVISIBLE (-5125 1375);
FORCEPROP 2 LAST CDS_LIB mstr_standard
J 0
(-5450 1500);
PAINT ORANGE (-5450 1500);
DISPLAY INVISIBLE (-5450 1500);
FORCEPROP 2 LAST PATH I39
J 0
(-5725 1550);
DISPLAY 1.021277 (-5725 1550);
PAINT ORANGE (-5725 1550);
DISPLAY INVISIBLE (-5725 1550);
FORCEADD OFFPAGE..1
(-5450 1450);
FORCEPROP 2 LAST $XR1 247 
J 0
(-5852 1450);
DISPLAY 0.638298 (-5852 1450);
PAINT MONO (-5852 1450);
FORCEPROP 2 LAST $XR0 155 
J 0
(-5732 1450);
DISPLAY 0.638298 (-5732 1450);
PAINT MONO (-5732 1450);
FORCEPROP 2 LAST CDS_LIB mstr_standard
J 0
(-5450 1450);
PAINT ORANGE (-5450 1450);
DISPLAY INVISIBLE (-5450 1450);
FORCEPROP 1 LAST COMMENT_BODY TRUE
J 0
(-5325 1350);
DISPLAY 0.872340 (-5325 1350);
PAINT GREEN (-5325 1350);
DISPLAY INVISIBLE (-5325 1350);
FORCEPROP 1 LAST OFFPAGE TRUE
J 0
(-5125 1325);
DISPLAY 0.872340 (-5125 1325);
PAINT GREEN (-5125 1325);
DISPLAY INVISIBLE (-5125 1325);
FORCEPROP 2 LAST PATH I40
J 0
(-5725 1500);
DISPLAY 1.021277 (-5725 1500);
PAINT ORANGE (-5725 1500);
DISPLAY INVISIBLE (-5725 1500);
FORCEADD GND..1
(-4825 1125);
FORCEPROP 3 LASTPIN (-4825 1175) SIG_NAME GND\g
J 0
(-4815 1185);
DISPLAY 0.659574 (-4815 1185);
PAINT MONO (-4815 1185);
DISPLAY INVISIBLE (-4815 1185);
FORCEPROP 1 LAST PATH I41
J 0
(-4750 1125);
DISPLAY 0.872340 (-4750 1125);
PAINT AQUA (-4750 1125);
DISPLAY INVISIBLE (-4750 1125);
FORCEPROP 1 LAST SIZE 1B
J 0
(-4750 1075);
DISPLAY 0.872340 (-4750 1075);
PAINT AQUA (-4750 1075);
DISPLAY INVISIBLE (-4750 1075);
FORCEPROP 1 LAST HDL_POWER GND
J 0
(-4825 1275);
DISPLAY 0.872340 (-4825 1275);
PAINT GREEN (-4825 1275);
DISPLAY INVISIBLE (-4825 1275);
FORCEPROP 1 LAST BODY_TYPE PLUMBING
J 0
(-4870 1082);
DISPLAY 0.340426 (-4870 1082);
PAINT GREEN (-4870 1082);
DISPLAY INVISIBLE (-4870 1082);
FORCEPROP 2 LAST CDS_LIB mstr_symbols
J 0
(-4825 1125);
PAINT ORANGE (-4825 1125);
DISPLAY INVISIBLE (-4825 1125);
FORCEPROP 1 LAST VOLTAGE 0.0V
J 0
(-4870 1082);
DISPLAY 0.340426 (-4870 1082);
PAINT SKYBLUE (-4870 1082);
DISPLAY INVISIBLE (-4870 1082);
FORCEADD OFFPAGE..5
(-5475 1350);
FORCEPROP 2 LAST $XR3 190 
J 0
(-6090 1350);
DISPLAY 0.638298 (-6090 1350);
PAINT MONO (-6090 1350);
FORCEPROP 2 LAST $XR2 175 
J 0
(-5970 1350);
DISPLAY 0.638298 (-5970 1350);
PAINT MONO (-5970 1350);
FORCEPROP 2 LAST $XR1 247 
J 0
(-5850 1350);
DISPLAY 0.638298 (-5850 1350);
PAINT MONO (-5850 1350);
FORCEPROP 2 LAST $XR0 111 
J 0
(-5730 1350);
DISPLAY 0.638298 (-5730 1350);
PAINT MONO (-5730 1350);
FORCEPROP 1 LAST OFFPAGE TRUE
J 0
(-5150 1225);
DISPLAY 0.872340 (-5150 1225);
PAINT GREEN (-5150 1225);
DISPLAY INVISIBLE (-5150 1225);
FORCEPROP 1 LAST COMMENT_BODY TRUE
J 0
(-5375 1275);
DISPLAY 0.872340 (-5375 1275);
PAINT GREEN (-5375 1275);
DISPLAY INVISIBLE (-5375 1275);
FORCEPROP 2 LAST CDS_LIB mstr_standard
J 0
(-5475 1350);
PAINT ORANGE (-5475 1350);
DISPLAY INVISIBLE (-5475 1350);
FORCEPROP 2 LAST PATH I42
J 0
(-5675 1400);
DISPLAY 1.021277 (-5675 1400);
PAINT ORANGE (-5675 1400);
DISPLAY INVISIBLE (-5675 1400);
FORCEADD OFFPAGE..1
(-5450 1400);
FORCEPROP 2 LAST $XR0 176 
J 0
(-5732 1400);
DISPLAY 0.638298 (-5732 1400);
PAINT MONO (-5732 1400);
FORCEPROP 2 LAST PATH I43
J 0
(-5725 1450);
DISPLAY 1.021277 (-5725 1450);
PAINT ORANGE (-5725 1450);
DISPLAY INVISIBLE (-5725 1450);
FORCEPROP 2 LAST CDS_LIB mstr_standard
J 0
(-5450 1400);
PAINT ORANGE (-5450 1400);
DISPLAY INVISIBLE (-5450 1400);
FORCEPROP 1 LAST COMMENT_BODY TRUE
J 0
(-5325 1300);
DISPLAY 0.872340 (-5325 1300);
PAINT GREEN (-5325 1300);
DISPLAY INVISIBLE (-5325 1300);
FORCEPROP 1 LAST OFFPAGE TRUE
J 0
(-5125 1275);
DISPLAY 0.872340 (-5125 1275);
PAINT GREEN (-5125 1275);
DISPLAY INVISIBLE (-5125 1275);
FORCEADD OFFPAGE..2
(-450 1400);
FORCEPROP 2 LAST $XR0 176 
J 0
(-261 1400);
DISPLAY 0.638298 (-261 1400);
PAINT MONO (-261 1400);
FORCEPROP 1 LAST COMMENT_BODY TRUE
J 0
(-495 1305);
DISPLAY 0.872340 (-495 1305);
PAINT GREEN (-495 1305);
DISPLAY INVISIBLE (-495 1305);
FORCEPROP 2 LAST CDS_LIB mstr_standard
J 0
(-450 1400);
PAINT ORANGE (-450 1400);
DISPLAY INVISIBLE (-450 1400);
FORCEPROP 2 LAST PATH I52
J 0
(-250 1450);
DISPLAY 1.021277 (-250 1450);
PAINT ORANGE (-250 1450);
DISPLAY INVISIBLE (-250 1450);
FORCEPROP 1 LAST OFFPAGE TRUE
J 0
(-125 1275);
DISPLAY 0.872340 (-125 1275);
PAINT GREEN (-125 1275);
DISPLAY INVISIBLE (-125 1275);
FORCEADD RES..1
(-1125 1400);
FORCEPROP 1 LAST VALUE 0.0
J 2
(-1150 1300);
DISPLAY 0.617021 (-1150 1300);
PAINT SKYBLUE (-1150 1300);
FORCEPROP 1 LAST WATTAGE 1/16W
J 2
(-1150 1250);
DISPLAY 0.617021 (-1150 1250);
PAINT SKYBLUE (-1150 1250);
FORCEPROP 1 LAST PART_NUMBER G21497-005
J 0
(-1175 1500);
DISPLAY 0.617021 (-1175 1500);
PAINT BLUE (-1175 1500);
FORCEPROP 1 LASTPIN (-1025 1400) $PN 2
J 0
(-1063 1412);
DISPLAY 0.617021 (-1063 1412);
PAINT ORANGE (-1063 1412);
FORCEPROP 1 LAST TOLERANCE 5%
J 0
(-1125 1300);
DISPLAY 0.617021 (-1125 1300);
PAINT SKYBLUE (-1125 1300);
FORCEPROP 1 LAST MATERIAL CHIP
J 0
(-1125 1250);
DISPLAY 0.617021 (-1125 1250);
PAINT SKYBLUE (-1125 1250);
FORCEPROP 1 LAST PACK_TYPE 0402
J 0
(-1000 1250);
DISPLAY 0.617021 (-1000 1250);
PAINT SKYBLUE (-1000 1250);
FORCEPROP 1 LAST LOCATION R9A8
J 0
(-1175 1450);
DISPLAY 0.617021 (-1175 1450);
PAINT AQUA (-1175 1450);
FORCEPROP 1 LASTPIN (-1225 1400) $PN 1
J 0
(-1213 1412);
DISPLAY 0.617021 (-1213 1412);
PAINT ORANGE (-1213 1412);
FORCEPROP 2 LAST CDS_LOCATION R9A8
J 0
(-1175 1450);
DISPLAY 0.617021 (-1175 1450);
PAINT AQUA (-1175 1450);
DISPLAY INVISIBLE (-1175 1450);
FORCEPROP 2 LAST CDS_LIB mstr_discrete
J 0
(-1125 1400);
PAINT ORANGE (-1125 1400);
DISPLAY INVISIBLE (-1125 1400);
FORCEPROP 2 LAST ROOM BMC_DEBUG_HEADER
J 0
(-1175 1550);
DISPLAY 1.021277 (-1175 1550);
PAINT ORANGE (-1175 1550);
DISPLAY INVISIBLE (-1175 1550);
FORCEPROP 1 LAST PATH I53
J 0
(-1175 1550);
DISPLAY 0.978723 (-1175 1550);
PAINT WHITE (-1175 1550);
DISPLAY INVISIBLE (-1175 1550);
FORCEPROP 2 LAST SEC 1
J 0
(-1175 1600);
PAINT MONO (-1175 1600);
DISPLAY INVISIBLE (-1175 1600);
FORCEPROP 2 LAST SEC_TYPE 0402
J 0
(-1175 1600);
DISPLAY 1.021277 (-1175 1600);
PAINT ORANGE (-1175 1600);
DISPLAY INVISIBLE (-1175 1600);
FORCEPROP 2 LAST BOM_COST DEBUG
J 0
(-1175 1600);
DISPLAY 1.021277 (-1175 1600);
PAINT ORANGE (-1175 1600);
DISPLAY INVISIBLE (-1175 1600);
FORCEADD OFFPAGE..3
(-2850 850);
FORCEPROP 2 LAST $XR1 247 
J 0
(-2516 850);
DISPLAY 0.638298 (-2516 850);
PAINT MONO (-2516 850);
FORCEPROP 2 LAST $XR0 168 
J 0
(-2636 850);
DISPLAY 0.638298 (-2636 850);
PAINT MONO (-2636 850);
FORCEPROP 2 LAST PATH I55
J 0
(-2650 925);
DISPLAY 1.021277 (-2650 925);
PAINT ORANGE (-2650 925);
DISPLAY INVISIBLE (-2650 925);
FORCEPROP 1 LAST OFFPAGE TRUE
J 0
(-2525 725);
DISPLAY 0.872340 (-2525 725);
PAINT GREEN (-2525 725);
DISPLAY INVISIBLE (-2525 725);
FORCEPROP 2 LAST CDS_LIB mstr_standard
J 0
(-2850 850);
PAINT ORANGE (-2850 850);
DISPLAY INVISIBLE (-2850 850);
FORCEPROP 1 LAST COMMENT_BODY TRUE
J 0
(-2900 750);
DISPLAY 0.872340 (-2900 750);
PAINT GREEN (-2900 750);
DISPLAY INVISIBLE (-2900 750);
FORCEADD OFFPAGE..1
(-7475 4050);
FORCEPROP 2 LAST $XR0 146 
J 0
(-7757 4050);
DISPLAY 0.638298 (-7757 4050);
PAINT MONO (-7757 4050);
FORCEPROP 2 LAST CDS_LIB mstr_standard
J 0
(-7475 4050);
PAINT ORANGE (-7475 4050);
DISPLAY INVISIBLE (-7475 4050);
FORCEPROP 1 LAST COMMENT_BODY TRUE
J 0
(-7350 3950);
DISPLAY 0.872340 (-7350 3950);
PAINT GREEN (-7350 3950);
DISPLAY INVISIBLE (-7350 3950);
FORCEPROP 1 LAST OFFPAGE TRUE
J 0
(-7150 3925);
DISPLAY 0.872340 (-7150 3925);
PAINT GREEN (-7150 3925);
DISPLAY INVISIBLE (-7150 3925);
FORCEPROP 2 LAST PATH I56
J 0
(-7725 4100);
DISPLAY 1.021277 (-7725 4100);
PAINT ORANGE (-7725 4100);
DISPLAY INVISIBLE (-7725 4100);
FORCEADD OFFPAGE..1
(-7475 3900);
FORCEPROP 2 LAST $XR0 146 
J 0
(-7757 3900);
DISPLAY 0.638298 (-7757 3900);
PAINT MONO (-7757 3900);
FORCEPROP 2 LAST PATH I57
J 0
(-7725 3950);
DISPLAY 1.021277 (-7725 3950);
PAINT ORANGE (-7725 3950);
DISPLAY INVISIBLE (-7725 3950);
FORCEPROP 2 LAST CDS_LIB mstr_standard
J 0
(-7475 3900);
PAINT ORANGE (-7475 3900);
DISPLAY INVISIBLE (-7475 3900);
FORCEPROP 1 LAST COMMENT_BODY TRUE
J 0
(-7350 3800);
DISPLAY 0.872340 (-7350 3800);
PAINT GREEN (-7350 3800);
DISPLAY INVISIBLE (-7350 3800);
FORCEPROP 1 LAST OFFPAGE TRUE
J 0
(-7150 3775);
DISPLAY 0.872340 (-7150 3775);
PAINT GREEN (-7150 3775);
DISPLAY INVISIBLE (-7150 3775);
FORCEADD OFFPAGE..1
(-7475 3750);
FORCEPROP 2 LAST $XR0 146 
J 0
(-7757 3750);
DISPLAY 0.638298 (-7757 3750);
PAINT MONO (-7757 3750);
FORCEPROP 2 LAST PATH I58
J 0
(-7725 3800);
DISPLAY 1.021277 (-7725 3800);
PAINT ORANGE (-7725 3800);
DISPLAY INVISIBLE (-7725 3800);
FORCEPROP 2 LAST CDS_LIB mstr_standard
J 0
(-7475 3750);
PAINT ORANGE (-7475 3750);
DISPLAY INVISIBLE (-7475 3750);
FORCEPROP 1 LAST COMMENT_BODY TRUE
J 0
(-7350 3650);
DISPLAY 0.872340 (-7350 3650);
PAINT GREEN (-7350 3650);
DISPLAY INVISIBLE (-7350 3650);
FORCEPROP 1 LAST OFFPAGE TRUE
J 0
(-7150 3625);
DISPLAY 0.872340 (-7150 3625);
PAINT GREEN (-7150 3625);
DISPLAY INVISIBLE (-7150 3625);
FORCEADD OFFPAGE..1
(-7475 3600);
FORCEPROP 2 LAST $XR0 146 
J 0
(-7757 3600);
DISPLAY 0.638298 (-7757 3600);
PAINT MONO (-7757 3600);
FORCEPROP 2 LAST CDS_LIB mstr_standard
J 0
(-7475 3600);
PAINT ORANGE (-7475 3600);
DISPLAY INVISIBLE (-7475 3600);
FORCEPROP 2 LAST PATH I59
J 0
(-7725 3650);
DISPLAY 1.021277 (-7725 3650);
PAINT ORANGE (-7725 3650);
DISPLAY INVISIBLE (-7725 3650);
FORCEPROP 1 LAST COMMENT_BODY TRUE
J 0
(-7350 3500);
DISPLAY 0.872340 (-7350 3500);
PAINT GREEN (-7350 3500);
DISPLAY INVISIBLE (-7350 3500);
FORCEPROP 1 LAST OFFPAGE TRUE
J 0
(-7150 3475);
DISPLAY 0.872340 (-7150 3475);
PAINT GREEN (-7150 3475);
DISPLAY INVISIBLE (-7150 3475);
FORCEADD OFFPAGE..1
(-7475 4200);
FORCEPROP 2 LAST $XR0 146 
J 0
(-7757 4200);
DISPLAY 0.638298 (-7757 4200);
PAINT MONO (-7757 4200);
FORCEPROP 1 LAST OFFPAGE TRUE
J 0
(-7150 4075);
DISPLAY 0.872340 (-7150 4075);
PAINT GREEN (-7150 4075);
DISPLAY INVISIBLE (-7150 4075);
FORCEPROP 1 LAST COMMENT_BODY TRUE
J 0
(-7350 4100);
DISPLAY 0.872340 (-7350 4100);
PAINT GREEN (-7350 4100);
DISPLAY INVISIBLE (-7350 4100);
FORCEPROP 2 LAST PATH I60
J 0
(-7725 4250);
DISPLAY 1.021277 (-7725 4250);
PAINT ORANGE (-7725 4250);
DISPLAY INVISIBLE (-7725 4250);
FORCEPROP 2 LAST CDS_LIB mstr_standard
J 0
(-7475 4200);
PAINT ORANGE (-7475 4200);
DISPLAY INVISIBLE (-7475 4200);
FORCEADD OFFPAGE..2
(-6050 3600);
FORCEPROP 2 LAST $XR1 155 
J 0
(-5741 3600);
DISPLAY 0.638298 (-5741 3600);
PAINT MONO (-5741 3600);
FORCEPROP 2 LAST $XR0 247 
J 0
(-5861 3600);
DISPLAY 0.638298 (-5861 3600);
PAINT MONO (-5861 3600);
FORCEPROP 1 LAST COMMENT_BODY TRUE
J 0
(-6095 3505);
DISPLAY 0.872340 (-6095 3505);
PAINT GREEN (-6095 3505);
DISPLAY INVISIBLE (-6095 3505);
FORCEPROP 2 LAST CDS_LIB mstr_standard
J 0
(-6050 3600);
PAINT ORANGE (-6050 3600);
DISPLAY INVISIBLE (-6050 3600);
FORCEPROP 1 LAST OFFPAGE TRUE
J 0
(-5725 3475);
DISPLAY 0.872340 (-5725 3475);
PAINT GREEN (-5725 3475);
DISPLAY INVISIBLE (-5725 3475);
FORCEPROP 2 LAST PATH I61
J 0
(-5825 3650);
DISPLAY 1.021277 (-5825 3650);
PAINT ORANGE (-5825 3650);
DISPLAY INVISIBLE (-5825 3650);
FORCEADD OFFPAGE..2
(-6050 4350);
FORCEPROP 2 LAST $XR1 155 
J 0
(-5741 4350);
DISPLAY 0.638298 (-5741 4350);
PAINT MONO (-5741 4350);
FORCEPROP 2 LAST $XR0 247 
J 0
(-5861 4350);
DISPLAY 0.638298 (-5861 4350);
PAINT MONO (-5861 4350);
FORCEPROP 1 LAST COMMENT_BODY TRUE
J 0
(-6095 4255);
DISPLAY 0.872340 (-6095 4255);
PAINT GREEN (-6095 4255);
DISPLAY INVISIBLE (-6095 4255);
FORCEPROP 2 LAST CDS_LIB mstr_standard
J 0
(-6050 4350);
PAINT ORANGE (-6050 4350);
DISPLAY INVISIBLE (-6050 4350);
FORCEPROP 2 LAST PATH I62
J 0
(-5825 4400);
DISPLAY 1.021277 (-5825 4400);
PAINT ORANGE (-5825 4400);
DISPLAY INVISIBLE (-5825 4400);
FORCEPROP 1 LAST OFFPAGE TRUE
J 0
(-5725 4225);
DISPLAY 0.872340 (-5725 4225);
PAINT GREEN (-5725 4225);
DISPLAY INVISIBLE (-5725 4225);
FORCEADD OFFPAGE..2
(-6050 4500);
FORCEPROP 2 LAST $XR1 155 
J 0
(-5741 4500);
DISPLAY 0.638298 (-5741 4500);
PAINT MONO (-5741 4500);
FORCEPROP 2 LAST $XR0 247 
J 0
(-5861 4500);
DISPLAY 0.638298 (-5861 4500);
PAINT MONO (-5861 4500);
FORCEPROP 1 LAST COMMENT_BODY TRUE
J 0
(-6095 4405);
DISPLAY 0.872340 (-6095 4405);
PAINT GREEN (-6095 4405);
DISPLAY INVISIBLE (-6095 4405);
FORCEPROP 2 LAST CDS_LIB mstr_standard
J 0
(-6050 4500);
PAINT ORANGE (-6050 4500);
DISPLAY INVISIBLE (-6050 4500);
FORCEPROP 2 LAST PATH I63
J 0
(-5825 4550);
DISPLAY 1.021277 (-5825 4550);
PAINT ORANGE (-5825 4550);
DISPLAY INVISIBLE (-5825 4550);
FORCEPROP 1 LAST OFFPAGE TRUE
J 0
(-5725 4375);
DISPLAY 0.872340 (-5725 4375);
PAINT GREEN (-5725 4375);
DISPLAY INVISIBLE (-5725 4375);
FORCEADD OFFPAGE..2
(-6050 4650);
FORCEPROP 2 LAST $XR1 155 
J 0
(-5741 4650);
DISPLAY 0.638298 (-5741 4650);
PAINT MONO (-5741 4650);
FORCEPROP 2 LAST $XR0 247 
J 0
(-5861 4650);
DISPLAY 0.638298 (-5861 4650);
PAINT MONO (-5861 4650);
FORCEPROP 1 LAST COMMENT_BODY TRUE
J 0
(-6095 4555);
DISPLAY 0.872340 (-6095 4555);
PAINT GREEN (-6095 4555);
DISPLAY INVISIBLE (-6095 4555);
FORCEPROP 2 LAST CDS_LIB mstr_standard
J 0
(-6050 4650);
PAINT ORANGE (-6050 4650);
DISPLAY INVISIBLE (-6050 4650);
FORCEPROP 2 LAST PATH I64
J 0
(-5825 4700);
DISPLAY 1.021277 (-5825 4700);
PAINT ORANGE (-5825 4700);
DISPLAY INVISIBLE (-5825 4700);
FORCEPROP 1 LAST OFFPAGE TRUE
J 0
(-5725 4525);
DISPLAY 0.872340 (-5725 4525);
PAINT GREEN (-5725 4525);
DISPLAY INVISIBLE (-5725 4525);
FORCEADD RES..1
(-6900 4650);
FORCEPROP 1 LASTPIN (-7000 4650) $PN 1
J 0
(-6988 4662);
DISPLAY 0.617021 (-6988 4662);
PAINT ORANGE (-6988 4662);
FORCEPROP 1 LASTPIN (-6800 4650) $PN 2
J 0
(-6838 4662);
DISPLAY 0.617021 (-6838 4662);
PAINT ORANGE (-6838 4662);
FORCEPROP 1 LAST PACK_TYPE 0402
J 0
(-6750 4600);
DISPLAY 0.617021 (-6750 4600);
PAINT SKYBLUE (-6750 4600);
FORCEPROP 1 LAST MATERIAL CHIP
J 0
(-6750 4725);
DISPLAY 0.638298 (-6750 4725);
PAINT SKYBLUE (-6750 4725);
FORCEPROP 1 LAST LOCATION R1L32
J 0
(-7150 4725);
DISPLAY 0.617021 (-7150 4725);
PAINT AQUA (-7150 4725);
FORCEPROP 1 LAST WATTAGE 1/16W
J 2
(-7025 4600);
DISPLAY 0.617021 (-7025 4600);
PAINT SKYBLUE (-7025 4600);
FORCEPROP 1 LAST VALUE 10.0
J 2
(-6925 4600);
DISPLAY 0.617021 (-6925 4600);
PAINT SKYBLUE (-6925 4600);
FORCEPROP 1 LAST TOLERANCE 1%
J 0
(-6850 4600);
DISPLAY 0.617021 (-6850 4600);
PAINT SKYBLUE (-6850 4600);
FORCEPROP 1 LAST PART_NUMBER G21796-066
J 0
(-7000 4725);
DISPLAY 0.617021 (-7000 4725);
PAINT BLUE (-7000 4725);
FORCEPROP 2 LAST BOM_COST DEBUG
J 0
(-6950 4800);
DISPLAY 1.021277 (-6950 4800);
PAINT ORANGE (-6950 4800);
DISPLAY INVISIBLE (-6950 4800);
FORCEPROP 2 LAST CDS_SEC 1
J 0
(-6950 4850);
PAINT MONO (-6950 4850);
DISPLAY INVISIBLE (-6950 4850);
FORCEPROP 2 LAST $SEC 1
J 0
(-6950 4850);
PAINT MONO (-6950 4850);
DISPLAY INVISIBLE (-6950 4850);
FORCEPROP 2 LAST CDS_LOCATION R1L32
J 0
(-6950 4700);
DISPLAY 0.617021 (-6950 4700);
PAINT AQUA (-6950 4700);
DISPLAY INVISIBLE (-6950 4700);
FORCEPROP 1 LAST PATH I65
J 0
(-6950 4800);
DISPLAY 0.978723 (-6950 4800);
PAINT WHITE (-6950 4800);
DISPLAY INVISIBLE (-6950 4800);
FORCEPROP 2 LAST ROOM BMC_DEBUG_HEADER
J 0
(-6950 4750);
DISPLAY 1.021277 (-6950 4750);
PAINT ORANGE (-6950 4750);
DISPLAY INVISIBLE (-6950 4750);
FORCEPROP 2 LAST CDS_LIB mstr_discrete
J 0
(-6900 4650);
PAINT ORANGE (-6900 4650);
DISPLAY INVISIBLE (-6900 4650);
FORCEADD RES..1
(-6900 4500);
FORCEPROP 1 LAST VALUE 10.0
J 2
(-6925 4450);
DISPLAY 0.617021 (-6925 4450);
PAINT SKYBLUE (-6925 4450);
FORCEPROP 1 LASTPIN (-6800 4500) $PN 2
J 0
(-6838 4512);
DISPLAY 0.617021 (-6838 4512);
PAINT ORANGE (-6838 4512);
FORCEPROP 1 LASTPIN (-7000 4500) $PN 1
J 0
(-6988 4512);
DISPLAY 0.617021 (-6988 4512);
PAINT ORANGE (-6988 4512);
FORCEPROP 1 LAST LOCATION R1L30
J 0
(-7150 4550);
DISPLAY 0.617021 (-7150 4550);
PAINT AQUA (-7150 4550);
FORCEPROP 1 LAST TOLERANCE 1%
J 0
(-6850 4450);
DISPLAY 0.617021 (-6850 4450);
PAINT SKYBLUE (-6850 4450);
FORCEPROP 1 LAST WATTAGE 1/16W
J 2
(-7025 4450);
DISPLAY 0.617021 (-7025 4450);
PAINT SKYBLUE (-7025 4450);
FORCEPROP 1 LAST PART_NUMBER G21796-066
J 0
(-7000 4550);
DISPLAY 0.617021 (-7000 4550);
PAINT BLUE (-7000 4550);
FORCEPROP 1 LAST MATERIAL CHIP
J 0
(-6750 4550);
DISPLAY 0.638298 (-6750 4550);
PAINT SKYBLUE (-6750 4550);
FORCEPROP 1 LAST PACK_TYPE 0402
J 0
(-6750 4450);
DISPLAY 0.617021 (-6750 4450);
PAINT SKYBLUE (-6750 4450);
FORCEPROP 2 LAST CDS_LOCATION R1L30
J 0
(-6950 4550);
DISPLAY 0.617021 (-6950 4550);
PAINT AQUA (-6950 4550);
DISPLAY INVISIBLE (-6950 4550);
FORCEPROP 2 LAST ROOM BMC_DEBUG_HEADER
J 0
(-6950 4600);
DISPLAY 1.021277 (-6950 4600);
PAINT ORANGE (-6950 4600);
DISPLAY INVISIBLE (-6950 4600);
FORCEPROP 2 LAST BOM_COST DEBUG
J 0
(-6950 4650);
DISPLAY 1.021277 (-6950 4650);
PAINT ORANGE (-6950 4650);
DISPLAY INVISIBLE (-6950 4650);
FORCEPROP 2 LAST CDS_SEC 1
J 0
(-6950 4700);
PAINT MONO (-6950 4700);
DISPLAY INVISIBLE (-6950 4700);
FORCEPROP 2 LAST $SEC 1
J 0
(-6950 4700);
PAINT MONO (-6950 4700);
DISPLAY INVISIBLE (-6950 4700);
FORCEPROP 1 LAST PATH I66
J 0
(-6950 4650);
DISPLAY 0.978723 (-6950 4650);
PAINT WHITE (-6950 4650);
DISPLAY INVISIBLE (-6950 4650);
FORCEPROP 2 LAST CDS_LIB mstr_discrete
J 0
(-6900 4500);
PAINT ORANGE (-6900 4500);
DISPLAY INVISIBLE (-6900 4500);
FORCEADD RES..1
(-6900 4350);
FORCEPROP 1 LASTPIN (-7000 4350) $PN 1
J 0
(-6988 4362);
DISPLAY 0.617021 (-6988 4362);
PAINT ORANGE (-6988 4362);
FORCEPROP 1 LAST LOCATION R1L25
J 0
(-7150 4400);
DISPLAY 0.617021 (-7150 4400);
PAINT AQUA (-7150 4400);
FORCEPROP 1 LASTPIN (-6800 4350) $PN 2
J 0
(-6838 4362);
DISPLAY 0.617021 (-6838 4362);
PAINT ORANGE (-6838 4362);
FORCEPROP 1 LAST WATTAGE 1/16W
J 2
(-7025 4300);
DISPLAY 0.617021 (-7025 4300);
PAINT SKYBLUE (-7025 4300);
FORCEPROP 1 LAST TOLERANCE 1%
J 0
(-6850 4300);
DISPLAY 0.617021 (-6850 4300);
PAINT SKYBLUE (-6850 4300);
FORCEPROP 1 LAST PART_NUMBER G21796-066
J 0
(-7000 4400);
DISPLAY 0.617021 (-7000 4400);
PAINT BLUE (-7000 4400);
FORCEPROP 1 LAST VALUE 10.0
J 2
(-6925 4300);
DISPLAY 0.617021 (-6925 4300);
PAINT SKYBLUE (-6925 4300);
FORCEPROP 1 LAST PACK_TYPE 0402
J 0
(-6750 4300);
DISPLAY 0.617021 (-6750 4300);
PAINT SKYBLUE (-6750 4300);
FORCEPROP 1 LAST MATERIAL CHIP
J 0
(-6750 4400);
DISPLAY 0.638298 (-6750 4400);
PAINT SKYBLUE (-6750 4400);
FORCEPROP 1 LAST PATH I67
J 0
(-6950 4500);
DISPLAY 0.978723 (-6950 4500);
PAINT WHITE (-6950 4500);
DISPLAY INVISIBLE (-6950 4500);
FORCEPROP 2 LAST $SEC 1
J 0
(-6950 4550);
PAINT MONO (-6950 4550);
DISPLAY INVISIBLE (-6950 4550);
FORCEPROP 2 LAST CDS_SEC 1
J 0
(-6950 4550);
PAINT MONO (-6950 4550);
DISPLAY INVISIBLE (-6950 4550);
FORCEPROP 2 LAST CDS_LOCATION R1L25
J 0
(-6900 4375);
DISPLAY 0.617021 (-6900 4375);
PAINT AQUA (-6900 4375);
DISPLAY INVISIBLE (-6900 4375);
FORCEPROP 2 LAST CDS_LIB mstr_discrete
J 0
(-6900 4350);
PAINT ORANGE (-6900 4350);
DISPLAY INVISIBLE (-6900 4350);
FORCEPROP 2 LAST ROOM BMC_DEBUG_HEADER
J 0
(-6800 4425);
DISPLAY 1.021277 (-6800 4425);
PAINT ORANGE (-6800 4425);
DISPLAY INVISIBLE (-6800 4425);
FORCEPROP 2 LAST BOM_COST DEBUG
J 0
(-6800 4475);
DISPLAY 1.021277 (-6800 4475);
PAINT ORANGE (-6800 4475);
DISPLAY INVISIBLE (-6800 4475);
FORCEADD RES..1
(-6900 4200);
FORCEPROP 1 LAST VALUE 10.0
J 0
(-7000 4150);
DISPLAY 0.617021 (-7000 4150);
PAINT SKYBLUE (-7000 4150);
FORCEPROP 1 LAST PART_NUMBER G21796-066
J 0
(-7000 4250);
DISPLAY 0.617021 (-7000 4250);
PAINT BLUE (-7000 4250);
FORCEPROP 1 LAST TOLERANCE 1%
J 0
(-6850 4150);
DISPLAY 0.617021 (-6850 4150);
PAINT SKYBLUE (-6850 4150);
FORCEPROP 1 LASTPIN (-6800 4200) $PN 2
J 0
(-6838 4212);
DISPLAY 0.617021 (-6838 4212);
PAINT ORANGE (-6838 4212);
FORCEPROP 1 LAST WATTAGE 1/16W
J 0
(-7150 4150);
DISPLAY 0.617021 (-7150 4150);
PAINT SKYBLUE (-7150 4150);
FORCEPROP 1 LASTPIN (-7000 4200) $PN 1
J 0
(-6988 4212);
DISPLAY 0.617021 (-6988 4212);
PAINT ORANGE (-6988 4212);
FORCEPROP 1 LAST LOCATION R1L24
J 0
(-7150 4250);
DISPLAY 0.617021 (-7150 4250);
PAINT AQUA (-7150 4250);
FORCEPROP 1 LAST PACK_TYPE 0402
J 0
(-6750 4150);
DISPLAY 0.617021 (-6750 4150);
PAINT SKYBLUE (-6750 4150);
FORCEPROP 1 LAST MATERIAL CHIP
J 0
(-6750 4250);
DISPLAY 0.638298 (-6750 4250);
PAINT SKYBLUE (-6750 4250);
FORCEPROP 2 LAST CDS_LOCATION R1L24
J 0
(-6950 4250);
DISPLAY 0.617021 (-6950 4250);
PAINT AQUA (-6950 4250);
DISPLAY INVISIBLE (-6950 4250);
FORCEPROP 2 LAST ROOM BMC_DEBUG_HEADER
J 0
(-6950 4300);
DISPLAY 1.021277 (-6950 4300);
PAINT ORANGE (-6950 4300);
DISPLAY INVISIBLE (-6950 4300);
FORCEPROP 1 LAST PATH I68
J 0
(-6950 4350);
DISPLAY 0.978723 (-6950 4350);
PAINT WHITE (-6950 4350);
DISPLAY INVISIBLE (-6950 4350);
FORCEPROP 2 LAST BOM_COST DEBUG
J 0
(-6950 4350);
DISPLAY 1.021277 (-6950 4350);
PAINT ORANGE (-6950 4350);
DISPLAY INVISIBLE (-6950 4350);
FORCEPROP 2 LAST $SEC 1
J 0
(-6950 4400);
PAINT MONO (-6950 4400);
DISPLAY INVISIBLE (-6950 4400);
FORCEPROP 2 LAST CDS_SEC 1
J 0
(-6950 4400);
PAINT MONO (-6950 4400);
DISPLAY INVISIBLE (-6950 4400);
FORCEPROP 2 LAST CDS_LIB mstr_discrete
J 0
(-6900 4200);
PAINT ORANGE (-6900 4200);
DISPLAY INVISIBLE (-6900 4200);
FORCEADD OFFPAGE..2
(-6050 4200);
FORCEPROP 2 LAST $XR1 155 
J 0
(-5741 4200);
DISPLAY 0.638298 (-5741 4200);
PAINT MONO (-5741 4200);
FORCEPROP 2 LAST $XR0 247 
J 0
(-5861 4200);
DISPLAY 0.638298 (-5861 4200);
PAINT MONO (-5861 4200);
FORCEPROP 1 LAST OFFPAGE TRUE
J 0
(-5725 4075);
DISPLAY 0.872340 (-5725 4075);
PAINT GREEN (-5725 4075);
DISPLAY INVISIBLE (-5725 4075);
FORCEPROP 1 LAST COMMENT_BODY TRUE
J 0
(-6095 4105);
DISPLAY 0.872340 (-6095 4105);
PAINT GREEN (-6095 4105);
DISPLAY INVISIBLE (-6095 4105);
FORCEPROP 2 LAST CDS_LIB mstr_standard
J 0
(-6050 4200);
PAINT ORANGE (-6050 4200);
DISPLAY INVISIBLE (-6050 4200);
FORCEPROP 2 LAST PATH I69
J 0
(-5825 4250);
DISPLAY 1.021277 (-5825 4250);
PAINT ORANGE (-5825 4250);
DISPLAY INVISIBLE (-5825 4250);
FORCEADD OFFPAGE..2
(-6050 4050);
FORCEPROP 2 LAST $XR1 155 
J 0
(-5741 4050);
DISPLAY 0.638298 (-5741 4050);
PAINT MONO (-5741 4050);
FORCEPROP 2 LAST $XR0 247 
J 0
(-5861 4050);
DISPLAY 0.638298 (-5861 4050);
PAINT MONO (-5861 4050);
FORCEPROP 1 LAST COMMENT_BODY TRUE
J 0
(-6095 3955);
DISPLAY 0.872340 (-6095 3955);
PAINT GREEN (-6095 3955);
DISPLAY INVISIBLE (-6095 3955);
FORCEPROP 2 LAST CDS_LIB mstr_standard
J 0
(-6050 4050);
PAINT ORANGE (-6050 4050);
DISPLAY INVISIBLE (-6050 4050);
FORCEPROP 1 LAST OFFPAGE TRUE
J 0
(-5725 3925);
DISPLAY 0.872340 (-5725 3925);
PAINT GREEN (-5725 3925);
DISPLAY INVISIBLE (-5725 3925);
FORCEPROP 2 LAST PATH I70
J 0
(-5825 4100);
DISPLAY 1.021277 (-5825 4100);
PAINT ORANGE (-5825 4100);
DISPLAY INVISIBLE (-5825 4100);
FORCEADD OFFPAGE..2
(-6050 3900);
FORCEPROP 2 LAST $XR1 155 
J 0
(-5741 3900);
DISPLAY 0.638298 (-5741 3900);
PAINT MONO (-5741 3900);
FORCEPROP 2 LAST $XR0 247 
J 0
(-5861 3900);
DISPLAY 0.638298 (-5861 3900);
PAINT MONO (-5861 3900);
FORCEPROP 1 LAST COMMENT_BODY TRUE
J 0
(-6095 3805);
DISPLAY 0.872340 (-6095 3805);
PAINT GREEN (-6095 3805);
DISPLAY INVISIBLE (-6095 3805);
FORCEPROP 2 LAST CDS_LIB mstr_standard
J 0
(-6050 3900);
PAINT ORANGE (-6050 3900);
DISPLAY INVISIBLE (-6050 3900);
FORCEPROP 2 LAST PATH I71
J 0
(-5825 3950);
DISPLAY 1.021277 (-5825 3950);
PAINT ORANGE (-5825 3950);
DISPLAY INVISIBLE (-5825 3950);
FORCEPROP 1 LAST OFFPAGE TRUE
J 0
(-5725 3775);
DISPLAY 0.872340 (-5725 3775);
PAINT GREEN (-5725 3775);
DISPLAY INVISIBLE (-5725 3775);
FORCEADD OFFPAGE..2
(-6050 3750);
FORCEPROP 2 LAST $XR1 155 
J 0
(-5741 3750);
DISPLAY 0.638298 (-5741 3750);
PAINT MONO (-5741 3750);
FORCEPROP 2 LAST $XR0 247 
J 0
(-5861 3750);
DISPLAY 0.638298 (-5861 3750);
PAINT MONO (-5861 3750);
FORCEPROP 1 LAST COMMENT_BODY TRUE
J 0
(-6095 3655);
DISPLAY 0.872340 (-6095 3655);
PAINT GREEN (-6095 3655);
DISPLAY INVISIBLE (-6095 3655);
FORCEPROP 2 LAST CDS_LIB mstr_standard
J 0
(-6050 3750);
PAINT ORANGE (-6050 3750);
DISPLAY INVISIBLE (-6050 3750);
FORCEPROP 2 LAST PATH I72
J 0
(-5825 3800);
DISPLAY 1.021277 (-5825 3800);
PAINT ORANGE (-5825 3800);
DISPLAY INVISIBLE (-5825 3800);
FORCEPROP 1 LAST OFFPAGE TRUE
J 0
(-5725 3625);
DISPLAY 0.872340 (-5725 3625);
PAINT GREEN (-5725 3625);
DISPLAY INVISIBLE (-5725 3625);
FORCEADD RES..1
(-6900 4050);
FORCEPROP 1 LAST VALUE 10.0
J 2
(-6925 4000);
DISPLAY 0.617021 (-6925 4000);
PAINT SKYBLUE (-6925 4000);
FORCEPROP 1 LASTPIN (-6800 4050) $PN 2
J 0
(-6838 4062);
DISPLAY 0.617021 (-6838 4062);
PAINT ORANGE (-6838 4062);
FORCEPROP 1 LASTPIN (-7000 4050) $PN 1
J 0
(-6988 4062);
DISPLAY 0.617021 (-6988 4062);
PAINT ORANGE (-6988 4062);
FORCEPROP 1 LAST LOCATION R1L20
J 0
(-7150 4100);
DISPLAY 0.617021 (-7150 4100);
PAINT AQUA (-7150 4100);
FORCEPROP 1 LAST WATTAGE 1/16W
J 2
(-7025 4000);
DISPLAY 0.617021 (-7025 4000);
PAINT SKYBLUE (-7025 4000);
FORCEPROP 1 LAST MATERIAL CHIP
J 0
(-6750 4100);
DISPLAY 0.638298 (-6750 4100);
PAINT SKYBLUE (-6750 4100);
FORCEPROP 1 LAST TOLERANCE 1%
J 0
(-6850 4000);
DISPLAY 0.617021 (-6850 4000);
PAINT SKYBLUE (-6850 4000);
FORCEPROP 1 LAST PACK_TYPE 0402
J 0
(-6750 4000);
DISPLAY 0.617021 (-6750 4000);
PAINT SKYBLUE (-6750 4000);
FORCEPROP 1 LAST PART_NUMBER G21796-066
J 0
(-7000 4100);
DISPLAY 0.617021 (-7000 4100);
PAINT BLUE (-7000 4100);
FORCEPROP 2 LAST CDS_LIB mstr_discrete
J 0
(-6900 4050);
PAINT ORANGE (-6900 4050);
DISPLAY INVISIBLE (-6900 4050);
FORCEPROP 2 LAST CDS_LOCATION R1L20
J 0
(-6950 4100);
DISPLAY 0.617021 (-6950 4100);
PAINT AQUA (-6950 4100);
DISPLAY INVISIBLE (-6950 4100);
FORCEPROP 2 LAST ROOM BMC_DEBUG_HEADER
J 0
(-6950 4150);
DISPLAY 1.021277 (-6950 4150);
PAINT ORANGE (-6950 4150);
DISPLAY INVISIBLE (-6950 4150);
FORCEPROP 1 LAST PATH I73
J 0
(-6950 4200);
DISPLAY 0.978723 (-6950 4200);
PAINT WHITE (-6950 4200);
DISPLAY INVISIBLE (-6950 4200);
FORCEPROP 2 LAST $SEC 1
J 0
(-6950 4250);
PAINT MONO (-6950 4250);
DISPLAY INVISIBLE (-6950 4250);
FORCEPROP 2 LAST CDS_SEC 1
J 0
(-6950 4250);
PAINT MONO (-6950 4250);
DISPLAY INVISIBLE (-6950 4250);
FORCEPROP 2 LAST BOM_COST DEBUG
J 0
(-6950 4200);
DISPLAY 1.021277 (-6950 4200);
PAINT ORANGE (-6950 4200);
DISPLAY INVISIBLE (-6950 4200);
FORCEADD RES..1
(-6900 3900);
FORCEPROP 1 LAST PART_NUMBER G21796-066
J 0
(-7000 3950);
DISPLAY 0.617021 (-7000 3950);
PAINT BLUE (-7000 3950);
FORCEPROP 1 LAST TOLERANCE 1%
J 0
(-6850 3850);
DISPLAY 0.617021 (-6850 3850);
PAINT SKYBLUE (-6850 3850);
FORCEPROP 1 LAST VALUE 10.0
J 2
(-6925 3850);
DISPLAY 0.617021 (-6925 3850);
PAINT SKYBLUE (-6925 3850);
FORCEPROP 1 LAST WATTAGE 1/16W
J 2
(-7025 3850);
DISPLAY 0.617021 (-7025 3850);
PAINT SKYBLUE (-7025 3850);
FORCEPROP 1 LAST LOCATION R1L18
J 0
(-7150 3950);
DISPLAY 0.617021 (-7150 3950);
PAINT AQUA (-7150 3950);
FORCEPROP 1 LASTPIN (-7000 3900) $PN 1
J 0
(-6988 3912);
DISPLAY 0.617021 (-6988 3912);
PAINT ORANGE (-6988 3912);
FORCEPROP 1 LASTPIN (-6800 3900) $PN 2
J 0
(-6838 3912);
DISPLAY 0.617021 (-6838 3912);
PAINT ORANGE (-6838 3912);
FORCEPROP 1 LAST PACK_TYPE 0402
J 0
(-6750 3850);
DISPLAY 0.617021 (-6750 3850);
PAINT SKYBLUE (-6750 3850);
FORCEPROP 1 LAST MATERIAL CHIP
J 0
(-6750 3950);
DISPLAY 0.638298 (-6750 3950);
PAINT SKYBLUE (-6750 3950);
FORCEPROP 2 LAST CDS_LOCATION R1L18
J 0
(-6950 3950);
DISPLAY 0.617021 (-6950 3950);
PAINT AQUA (-6950 3950);
DISPLAY INVISIBLE (-6950 3950);
FORCEPROP 2 LAST ROOM BMC_DEBUG_HEADER
J 0
(-6950 4000);
DISPLAY 1.021277 (-6950 4000);
PAINT ORANGE (-6950 4000);
DISPLAY INVISIBLE (-6950 4000);
FORCEPROP 1 LAST PATH I74
J 0
(-6950 4050);
DISPLAY 0.978723 (-6950 4050);
PAINT WHITE (-6950 4050);
DISPLAY INVISIBLE (-6950 4050);
FORCEPROP 2 LAST BOM_COST DEBUG
J 0
(-6950 4050);
DISPLAY 1.021277 (-6950 4050);
PAINT ORANGE (-6950 4050);
DISPLAY INVISIBLE (-6950 4050);
FORCEPROP 2 LAST CDS_LIB mstr_discrete
J 0
(-6900 3900);
PAINT ORANGE (-6900 3900);
DISPLAY INVISIBLE (-6900 3900);
FORCEPROP 2 LAST $SEC 1
J 0
(-6950 4100);
PAINT MONO (-6950 4100);
DISPLAY INVISIBLE (-6950 4100);
FORCEPROP 2 LAST CDS_SEC 1
J 0
(-6950 4100);
PAINT MONO (-6950 4100);
DISPLAY INVISIBLE (-6950 4100);
FORCEADD RES..1
(-6900 3750);
FORCEPROP 1 LAST MATERIAL CHIP
J 0
(-6750 3800);
DISPLAY 0.638298 (-6750 3800);
PAINT SKYBLUE (-6750 3800);
FORCEPROP 1 LAST PACK_TYPE 0402
J 0
(-6750 3700);
DISPLAY 0.617021 (-6750 3700);
PAINT SKYBLUE (-6750 3700);
FORCEPROP 1 LAST VALUE 10.0
J 2
(-6925 3700);
DISPLAY 0.617021 (-6925 3700);
PAINT SKYBLUE (-6925 3700);
FORCEPROP 1 LAST TOLERANCE 1%
J 0
(-6850 3700);
DISPLAY 0.617021 (-6850 3700);
PAINT SKYBLUE (-6850 3700);
FORCEPROP 1 LAST PART_NUMBER G21796-066
J 0
(-7000 3800);
DISPLAY 0.617021 (-7000 3800);
PAINT BLUE (-7000 3800);
FORCEPROP 1 LAST WATTAGE 1/16W
J 2
(-7025 3700);
DISPLAY 0.617021 (-7025 3700);
PAINT SKYBLUE (-7025 3700);
FORCEPROP 1 LASTPIN (-6800 3750) $PN 2
J 0
(-6838 3762);
DISPLAY 0.617021 (-6838 3762);
PAINT ORANGE (-6838 3762);
FORCEPROP 1 LASTPIN (-7000 3750) $PN 1
J 0
(-6988 3762);
DISPLAY 0.617021 (-6988 3762);
PAINT ORANGE (-6988 3762);
FORCEPROP 1 LAST LOCATION R1L14
J 0
(-7150 3800);
DISPLAY 0.617021 (-7150 3800);
PAINT AQUA (-7150 3800);
FORCEPROP 2 LAST CDS_LOCATION R1L14
J 0
(-6950 3800);
DISPLAY 0.617021 (-6950 3800);
PAINT AQUA (-6950 3800);
DISPLAY INVISIBLE (-6950 3800);
FORCEPROP 2 LAST ROOM BMC_DEBUG_HEADER
J 0
(-6950 3850);
DISPLAY 1.021277 (-6950 3850);
PAINT ORANGE (-6950 3850);
DISPLAY INVISIBLE (-6950 3850);
FORCEPROP 1 LAST PATH I75
J 0
(-6950 3900);
DISPLAY 0.978723 (-6950 3900);
PAINT WHITE (-6950 3900);
DISPLAY INVISIBLE (-6950 3900);
FORCEPROP 2 LAST $SEC 1
J 0
(-6950 3950);
PAINT MONO (-6950 3950);
DISPLAY INVISIBLE (-6950 3950);
FORCEPROP 2 LAST CDS_SEC 1
J 0
(-6950 3950);
PAINT MONO (-6950 3950);
DISPLAY INVISIBLE (-6950 3950);
FORCEPROP 2 LAST BOM_COST DEBUG
J 0
(-6950 3900);
DISPLAY 1.021277 (-6950 3900);
PAINT ORANGE (-6950 3900);
DISPLAY INVISIBLE (-6950 3900);
FORCEPROP 2 LAST CDS_LIB mstr_discrete
J 0
(-6900 3750);
PAINT ORANGE (-6900 3750);
DISPLAY INVISIBLE (-6900 3750);
FORCEADD RES..1
(-6900 3600);
FORCEPROP 1 LAST MATERIAL CHIP
J 0
(-6750 3650);
DISPLAY 0.638298 (-6750 3650);
PAINT SKYBLUE (-6750 3650);
FORCEPROP 1 LAST PART_NUMBER G21796-066
J 0
(-7000 3650);
DISPLAY 0.617021 (-7000 3650);
PAINT BLUE (-7000 3650);
FORCEPROP 1 LAST VALUE 10.0
J 2
(-6925 3550);
DISPLAY 0.617021 (-6925 3550);
PAINT SKYBLUE (-6925 3550);
FORCEPROP 1 LAST LOCATION R1L11
J 0
(-7150 3650);
DISPLAY 0.617021 (-7150 3650);
PAINT AQUA (-7150 3650);
FORCEPROP 1 LASTPIN (-6800 3600) $PN 2
J 0
(-6838 3612);
DISPLAY 0.617021 (-6838 3612);
PAINT ORANGE (-6838 3612);
FORCEPROP 1 LASTPIN (-7000 3600) $PN 1
J 0
(-6988 3612);
DISPLAY 0.617021 (-6988 3612);
PAINT ORANGE (-6988 3612);
FORCEPROP 1 LAST TOLERANCE 1%
J 0
(-6850 3550);
DISPLAY 0.617021 (-6850 3550);
PAINT SKYBLUE (-6850 3550);
FORCEPROP 1 LAST WATTAGE 1/16W
J 2
(-7025 3550);
DISPLAY 0.617021 (-7025 3550);
PAINT SKYBLUE (-7025 3550);
FORCEPROP 1 LAST PACK_TYPE 0402
J 0
(-6750 3550);
DISPLAY 0.617021 (-6750 3550);
PAINT SKYBLUE (-6750 3550);
FORCEPROP 2 LAST BOM_COST DEBUG
J 0
(-6950 3750);
DISPLAY 1.021277 (-6950 3750);
PAINT ORANGE (-6950 3750);
DISPLAY INVISIBLE (-6950 3750);
FORCEPROP 2 LAST CDS_SEC 1
J 0
(-6950 3800);
PAINT MONO (-6950 3800);
DISPLAY INVISIBLE (-6950 3800);
FORCEPROP 2 LAST $SEC 1
J 0
(-6950 3800);
PAINT MONO (-6950 3800);
DISPLAY INVISIBLE (-6950 3800);
FORCEPROP 2 LAST CDS_LOCATION R1L11
J 0
(-6950 3650);
DISPLAY 0.617021 (-6950 3650);
PAINT AQUA (-6950 3650);
DISPLAY INVISIBLE (-6950 3650);
FORCEPROP 1 LAST PATH I76
J 0
(-6950 3750);
DISPLAY 0.978723 (-6950 3750);
PAINT WHITE (-6950 3750);
DISPLAY INVISIBLE (-6950 3750);
FORCEPROP 2 LAST ROOM BMC_DEBUG_HEADER
J 0
(-6950 3700);
DISPLAY 1.021277 (-6950 3700);
PAINT ORANGE (-6950 3700);
DISPLAY INVISIBLE (-6950 3700);
FORCEPROP 2 LAST CDS_LIB mstr_discrete
J 0
(-6900 3600);
PAINT ORANGE (-6900 3600);
DISPLAY INVISIBLE (-6900 3600);
FORCEADD OFFPAGE..1
(-7475 4500);
FORCEPROP 2 LAST $XR0 146 
J 0
(-7757 4500);
DISPLAY 0.638298 (-7757 4500);
PAINT MONO (-7757 4500);
FORCEPROP 2 LAST PATH I77
J 0
(-7725 4550);
DISPLAY 1.021277 (-7725 4550);
PAINT ORANGE (-7725 4550);
DISPLAY INVISIBLE (-7725 4550);
FORCEPROP 2 LAST CDS_LIB mstr_standard
J 0
(-7475 4500);
PAINT ORANGE (-7475 4500);
DISPLAY INVISIBLE (-7475 4500);
FORCEPROP 1 LAST COMMENT_BODY TRUE
J 0
(-7350 4400);
DISPLAY 0.872340 (-7350 4400);
PAINT GREEN (-7350 4400);
DISPLAY INVISIBLE (-7350 4400);
FORCEPROP 1 LAST OFFPAGE TRUE
J 0
(-7150 4375);
DISPLAY 0.872340 (-7150 4375);
PAINT GREEN (-7150 4375);
DISPLAY INVISIBLE (-7150 4375);
FORCEADD OFFPAGE..1
(-7475 4650);
FORCEPROP 2 LAST $XR0 146 
J 0
(-7757 4650);
DISPLAY 0.638298 (-7757 4650);
PAINT MONO (-7757 4650);
FORCEPROP 2 LAST PATH I78
J 0
(-7725 4700);
DISPLAY 1.021277 (-7725 4700);
PAINT ORANGE (-7725 4700);
DISPLAY INVISIBLE (-7725 4700);
FORCEPROP 2 LAST CDS_LIB mstr_standard
J 0
(-7475 4650);
PAINT ORANGE (-7475 4650);
DISPLAY INVISIBLE (-7475 4650);
FORCEPROP 1 LAST COMMENT_BODY TRUE
J 0
(-7350 4550);
DISPLAY 0.872340 (-7350 4550);
PAINT GREEN (-7350 4550);
DISPLAY INVISIBLE (-7350 4550);
FORCEPROP 1 LAST OFFPAGE TRUE
J 0
(-7150 4525);
DISPLAY 0.872340 (-7150 4525);
PAINT GREEN (-7150 4525);
DISPLAY INVISIBLE (-7150 4525);
FORCEADD OFFPAGE..1
(-7475 4350);
FORCEPROP 2 LAST $XR0 146 
J 0
(-7757 4350);
DISPLAY 0.638298 (-7757 4350);
PAINT MONO (-7757 4350);
FORCEPROP 2 LAST PATH I79
J 0
(-7725 4400);
DISPLAY 1.021277 (-7725 4400);
PAINT ORANGE (-7725 4400);
DISPLAY INVISIBLE (-7725 4400);
FORCEPROP 2 LAST CDS_LIB mstr_standard
J 0
(-7475 4350);
PAINT ORANGE (-7475 4350);
DISPLAY INVISIBLE (-7475 4350);
FORCEPROP 1 LAST COMMENT_BODY TRUE
J 0
(-7350 4250);
DISPLAY 0.872340 (-7350 4250);
PAINT GREEN (-7350 4250);
DISPLAY INVISIBLE (-7350 4250);
FORCEPROP 1 LAST OFFPAGE TRUE
J 0
(-7150 4225);
DISPLAY 0.872340 (-7150 4225);
PAINT GREEN (-7150 4225);
DISPLAY INVISIBLE (-7150 4225);
FORCEADD RES..2
(-1450 1725);
FORCEPROP 1 LAST PACK_TYPE 0402
J 0
(-1410 1550);
DISPLAY 0.617021 (-1410 1550);
PAINT SKYBLUE (-1410 1550);
FORCEPROP 1 LASTPIN (-1450 1825) $PN 1
J 0
(-1445 1787);
DISPLAY 0.617021 (-1445 1787);
PAINT ORANGE (-1445 1787);
FORCEPROP 1 LAST PART_NUMBER G21796-112
J 0
(-1410 1600);
DISPLAY 0.617021 (-1410 1600);
PAINT BLUE (-1410 1600);
FORCEPROP 1 LASTPIN (-1450 1625) $PN 2
J 0
(-1445 1635);
DISPLAY 0.617021 (-1445 1635);
PAINT ORANGE (-1445 1635);
FORCEPROP 1 LAST MATERIAL CHIP
J 0
(-1410 1650);
DISPLAY 0.617021 (-1410 1650);
PAINT SKYBLUE (-1410 1650);
FORCEPROP 1 LAST TOLERANCE 1%
J 0
(-1405 1750);
DISPLAY 0.617021 (-1405 1750);
PAINT SKYBLUE (-1405 1750);
FORCEPROP 1 LAST VALUE 2.21K
J 0
(-1405 1800);
DISPLAY 0.617021 (-1405 1800);
PAINT SKYBLUE (-1405 1800);
FORCEPROP 1 LAST WATTAGE 1/16W
J 0
(-1410 1700);
DISPLAY 0.617021 (-1410 1700);
PAINT SKYBLUE (-1410 1700);
FORCEPROP 1 LAST LOCATION R9A7
J 0
(-1405 1850);
DISPLAY 0.617021 (-1405 1850);
PAINT AQUA (-1405 1850);
FORCEPROP 2 LAST CDS_LIB mstr_discrete
J 0
(-1450 1725);
PAINT ORANGE (-1450 1725);
DISPLAY INVISIBLE (-1450 1725);
FORCEPROP 2 LAST SEC_TYPE 0402
J 0
(-1400 1950);
DISPLAY 1.021277 (-1400 1950);
PAINT ORANGE (-1400 1950);
DISPLAY INVISIBLE (-1400 1950);
FORCEPROP 2 LAST BOM_COST DEBUG
J 0
(-1400 1950);
DISPLAY 1.021277 (-1400 1950);
PAINT ORANGE (-1400 1950);
DISPLAY INVISIBLE (-1400 1950);
FORCEPROP 2 LAST SEC 1
J 0
(-1400 1950);
DISPLAY 0.680851 (-1400 1950);
PAINT MONO (-1400 1950);
DISPLAY INVISIBLE (-1400 1950);
FORCEPROP 2 LAST CDS_LOCATION R9A7
J 0
(-1405 1850);
DISPLAY 0.617021 (-1405 1850);
PAINT AQUA (-1405 1850);
DISPLAY INVISIBLE (-1405 1850);
FORCEPROP 1 LAST PATH I80
J 0
(-1400 1900);
DISPLAY 0.978723 (-1400 1900);
PAINT WHITE (-1400 1900);
DISPLAY INVISIBLE (-1400 1900);
FORCEPROP 2 LAST ROOM BMC_DEBUG_HEADER
J 0
(-1400 1900);
DISPLAY 1.021277 (-1400 1900);
PAINT ORANGE (-1400 1900);
DISPLAY INVISIBLE (-1400 1900);
FORCEADD P3V3_STBY..1
(-1450 1975);
FORCEPROP 3 LASTPIN (-1450 1925) SIG_NAME P3V3_STBY\g
J 0
(-1440 1935);
DISPLAY 0.659574 (-1440 1935);
PAINT MONO (-1440 1935);
DISPLAY INVISIBLE (-1440 1935);
FORCEPROP 1 LAST SIZE 1B
J 0
(-1405 1997);
DISPLAY 0.340426 (-1405 1997);
PAINT GREEN (-1405 1997);
DISPLAY INVISIBLE (-1405 1997);
FORCEPROP 1 LAST BODY_TYPE PLUMBING
J 0
(-1495 1932);
DISPLAY 0.340426 (-1495 1932);
PAINT GREEN (-1495 1932);
DISPLAY INVISIBLE (-1495 1932);
FORCEPROP 2 LAST CDS_LIB mstr_symbols
J 0
(-1450 1975);
PAINT ORANGE (-1450 1975);
DISPLAY INVISIBLE (-1450 1975);
FORCEPROP 1 LAST VOLTAGE 3.3V
J 0
(-1495 1932);
DISPLAY 0.340426 (-1495 1932);
PAINT SKYBLUE (-1495 1932);
DISPLAY INVISIBLE (-1495 1932);
FORCEPROP 1 LAST HDL_POWER P3V3_STBY
J 0
(-1750 1850);
DISPLAY 0.872340 (-1750 1850);
PAINT ORANGE (-1750 1850);
DISPLAY INVISIBLE (-1750 1850);
FORCEPROP 1 LAST PATH I81
J 0
(-1405 1977);
DISPLAY 0.340426 (-1405 1977);
PAINT GREEN (-1405 1977);
DISPLAY INVISIBLE (-1405 1977);
FORCEADD INTEL_CORP_BPAGE..1
(0 0);
FORCEPROP 1 LAST CDS_CON_LAST_MODIFIED Fri Jun 16 17:48:58 2017
J 0
(-1425 325);
DISPLAY 1.361702 (-1425 325);
PAINT GREEN (-1425 325);
DISPLAY INVISIBLE (-1425 325);
FORCEPROP 1 LAST CUSTOM_TXT_CDS <CURRENT_DESIGN_SHEET> OF <TOTAL_DESIGN_SHEETS>
J 0
(-500 25);
PAINT ORANGE (-500 25);
FORCEPROP 1 LAST CUSTOM_TXT_CDS <CON_LAST_MODIFIED>
J 0
(-4000 100);
PAINT ORANGE (-4000 100);
FORCEPROP 2 LAST CUSTOM_TXT_CDS <XR_PAGE_TITLE>
J 0
(-7890 5250);
DISPLAY 0.638298 (-7890 5250);
PAINT PINK (-7890 5250);
DISPLAY INVISIBLE (-7890 5250);
FORCEPROP 1 LAST SCH_TITLE BMC DEBUG HEADER
J 0
(-7950 50);
DISPLAY 1.212766 (-7950 50);
PAINT ORANGE (-7950 50);
FORCEPROP 1 LAST COMMENT_BODY TRUE
J 0
(12 12);
DISPLAY 0.617021 (12 12);
PAINT GREEN (12 12);
DISPLAY INVISIBLE (12 12);
FORCEPROP 2 LAST CDS_LIB mstr_symbols
J 0
(0 0);
DISPLAY 1.361702 (0 0);
PAINT ORANGE (0 0);
DISPLAY INVISIBLE (0 0);
FORCEPROP 2 LAST PAGE_BORDER TRUE
J 0
(-7890 5250);
DISPLAY 0.851064 (-7890 5250);
PAINT PINK (-7890 5250);
DISPLAY INVISIBLE (-7890 5250);
FORCEPROP 2 LAST CDS_XR_PAGE_TITLE CR-155 : @BASEBOARD_FAB2_LIB.BASEBOARD_FAB2(SCH_1):PAGE155
J 0
(-7890 5250);
DISPLAY 0.638298 (-7890 5250);
PAINT PINK (-7890 5250);
DISPLAY INVISIBLE (-7890 5250);
FORCEADD CAD_NOTE..1
(-1950 3175);
FORCEPROP 0 LAST L2 ON TTL1G07_A
J 2
(-1700 2975);
DISPLAY 1.021277 (-1700 2975);
PAINT ORANGE (-1700 2975);
FORCEPROP 0 LAST L1 PLACE 0.1UF CAP NEXT TO VCC PIN
J 2
(-1700 3050);
DISPLAY 1.021277 (-1700 3050);
PAINT ORANGE (-1700 3050);
FORCEPROP 2 LAST CDS_LIB mstr_symbols
J 0
(-1950 3175);
PAINT ORANGE (-1950 3175);
DISPLAY INVISIBLE (-1950 3175);
FORCEPROP 1 LAST COMMENT_BODY TRUE
J 0
(-1925 3275);
DISPLAY 0.978723 (-1925 3275);
PAINT ORANGE (-1925 3275);
DISPLAY INVISIBLE (-1925 3275);
WIRE 16 -1 (-4100 950)(-4100 875);
WIRE 16 -1 (-5950 1850)(-5950 1900);
WIRE 16 -1 (-1550 3275)(-1550 3125);
WIRE 16 -1 (-1550 2775)(-1550 2925);
WIRE 16 -1 (-5950 2850)(-5950 2675);
WIRE 16 -1 (-3350 1150)(-3350 1200);
WIRE 16 -1 (-5400 2625)(-5400 2700);
WIRE 16 -1 (-5400 2625)(-5150 2625);
WIRE 16 -1 (-2700 1900)(-2700 1800);
WIRE 16 -1 (-4825 1175)(-4825 1300);
WIRE 16 -1 (-4825 1300)(-4750 1300);
WIRE 16 -1 (-1450 1925)(-1450 1825);
WIRE 16 -1 (-6800 4500)(-6100 4500);
FORCEPROP 2 LAST SIG_NAME LED_POSTCODE_1_R
J 0
(-6450 4510);
DISPLAY 0.617021 (-6450 4510);
PAINT ORANGE (-6450 4510);
WIRE 3 2175 (-5525 2225)(-150 2225);
WIRE 3 2175 (-150 2225)(-150 800);
WIRE 3 2175 (-5525 2225)(-5525 800);
WIRE 3 2175 (-5525 800)(-150 800);
WIRE 16 -1 (-4150 1350)(-3600 1350);
FORCEPROP 2 LAST SIG_NAME FM_UART_SWITCH_N
J 0
(-4035 1360);
DISPLAY 0.617021 (-4035 1360);
PAINT ORANGE (-4035 1360);
WIRE 16 -1 (-3600 1350)(-3600 850);
WIRE 16 -1 (-3600 850)(-3350 850);
WIRE 16 -1 (-3350 950)(-3350 850);
WIRE 16 -1 (-3350 850)(-2900 850);
WIRE 16 -1 (-1850 1775)(-1525 1775);
WIRE 16 -1 (-1225 1400)(-1450 1400);
WIRE 16 -1 (-1450 1625)(-1450 1400);
WIRE 16 -1 (-1525 1400)(-1450 1400);
WIRE 16 -1 (-1525 1775)(-1525 1400);
WIRE 16 -1 (-1950 1400)(-1525 1400);
FORCEPROP 2 LAST SIG_NAME SPA_SIN_SW_R
J 0
(-1810 1410);
DISPLAY 0.617021 (-1810 1410);
PAINT ORANGE (-1810 1410);
FORCEPROP 2 LASTPROP $XRERR UNIQUE?
J 0
(-2050 1410);
DISPLAY 0.638298 (-2050 1410);
PAINT MONO (-2050 1410);
DISPLAY INVISIBLE (-2050 1410);
WIRE 16 -1 (-2800 1400)(-2700 1400);
WIRE 16 -1 (-2700 1600)(-2700 1400);
WIRE 16 -1 (-2275 1400)(-2700 1400);
FORCEPROP 2 LAST SIG_NAME SPA_5V_SIN_SW_D
J 0
(-2660 1425);
DISPLAY 0.617021 (-2660 1425);
PAINT ORANGE (-2660 1425);
FORCEPROP 2 LASTPROP $XRERR UNIQUE?
J 0
(-2900 1425);
DISPLAY 0.638298 (-2900 1425);
PAINT MONO (-2900 1425);
DISPLAY INVISIBLE (-2900 1425);
WIRE 16 -1 (-2275 1400)(-2200 1400);
WIRE 16 -1 (-2275 1400)(-2275 1775);
WIRE 16 -1 (-2275 1775)(-2050 1775);
WIRE 3 682 (-3050 1750)(-3050 1350);
WIRE 3 682 (-2750 1750)(-3050 1750);
WIRE 3 682 (-3050 1350)(-2750 1350);
WIRE 3 682 (-2750 1350)(-2750 1750);
WIRE 3 682 (-3500 750)(-3100 750);
WIRE 3 682 (-3500 1350)(-3500 750);
WIRE 3 682 (-3100 750)(-3100 1350);
WIRE 3 682 (-3100 1350)(-3500 1350);
WIRE 16 -1 (-4150 1550)(-3650 1550);
FORCEPROP 2 LAST SIG_NAME LED_POSTCODE_3_R
J 2
(-3650 1560);
DISPLAY 0.617021 (-3650 1560);
PAINT ORANGE (-3650 1560);
WIRE 16 -1 (-4150 1500)(-3650 1500);
FORCEPROP 2 LAST SIG_NAME LED_POSTCODE_5_R
J 2
(-3650 1510);
DISPLAY 0.617021 (-3650 1510);
PAINT ORANGE (-3650 1510);
WIRE 16 -1 (-4150 1450)(-3650 1450);
FORCEPROP 2 LAST SIG_NAME LED_POSTCODE_7_R
J 2
(-3650 1460);
DISPLAY 0.617021 (-3650 1460);
PAINT ORANGE (-3650 1460);
WIRE 16 -1 (-4150 1400)(-3000 1400);
FORCEPROP 2 LAST SIG_NAME SPA_5V_SIN_SW
J 0
(-4035 1400);
DISPLAY 0.617021 (-4035 1400);
PAINT ORANGE (-4035 1400);
FORCEPROP 2 LASTPROP $XRERR UNIQUE?
J 0
(-4275 1400);
DISPLAY 0.638298 (-4275 1400);
PAINT MONO (-4275 1400);
DISPLAY INVISIBLE (-4275 1400);
WIRE 16 -1 (-6800 4050)(-6100 4050);
FORCEPROP 2 LAST SIG_NAME LED_POSTCODE_4_R
J 0
(-6450 4060);
DISPLAY 0.617021 (-6450 4060);
PAINT ORANGE (-6450 4060);
WIRE 16 -1 (-6800 4350)(-6100 4350);
FORCEPROP 2 LAST SIG_NAME LED_POSTCODE_2_R
J 0
(-6450 4360);
DISPLAY 0.617021 (-6450 4360);
PAINT ORANGE (-6450 4360);
WIRE 16 -1 (-7425 4350)(-7000 4350);
FORCEPROP 2 LAST SIG_NAME LED_POSTCODE_2
J 0
(-7425 4360);
DISPLAY 0.617021 (-7425 4360);
PAINT ORANGE (-7425 4360);
WIRE 16 -1 (-1025 1400)(-500 1400);
FORCEPROP 2 LAST SIG_NAME SPA_MID_DBG1_RX
J 0
(-910 1410);
DISPLAY 0.617021 (-910 1410);
PAINT ORANGE (-910 1410);
WIRE 16 -1 (-4100 2625)(-4125 2625);
WIRE 16 -1 (-4100 1150)(-4100 1300);
WIRE 16 -1 (-4100 1300)(-4150 1300);
WIRE 16 -1 (-4100 1300)(-4100 2625);
FORCEPROP 0 LAST VOLTAGE 5
J 0
(-4100 1850);
DISPLAY 1.021277 (-4100 1850);
PAINT SKYBLUE (-4100 1850);
DISPLAY INVISIBLE (-4100 1850);
FORCEPROP 2 LAST SIG_NAME P5V_STBY_DGB_FS
R 1
J 0
(-4110 1785);
DISPLAY 0.617021 (-4110 1785);
PAINT ORANGE (-4110 1785);
FORCEPROP 2 LASTPROP $XRERR UNIQUE?
J 0
(-4350 1785);
DISPLAY 0.638298 (-4350 1785);
PAINT MONO (-4350 1785);
DISPLAY INVISIBLE (-4350 1785);
WIRE 16 -1 (-5400 1400)(-4750 1400);
FORCEPROP 2 LAST SIG_NAME SPA_MID_DBG1_TX
J 0
(-5410 1410);
DISPLAY 0.680851 (-5410 1410);
PAINT ORANGE (-5410 1410);
WIRE 16 -1 (-5425 1350)(-4750 1350);
FORCEPROP 2 LAST SIG_NAME FM_DEBUG_RST_BTN_N
J 0
(-5450 1360);
DISPLAY 0.617021 (-5450 1360);
PAINT ORANGE (-5450 1360);
WIRE 16 -1 (-5400 1600)(-4750 1600);
FORCEPROP 2 LAST SIG_NAME LED_POSTCODE_0_R
J 0
(-5425 1610);
DISPLAY 0.617021 (-5425 1610);
PAINT ORANGE (-5425 1610);
WIRE 16 -1 (-5400 1550)(-4750 1550);
FORCEPROP 2 LAST SIG_NAME LED_POSTCODE_2_R
J 0
(-5425 1560);
DISPLAY 0.617021 (-5425 1560);
PAINT ORANGE (-5425 1560);
WIRE 16 -1 (-7425 4500)(-7000 4500);
FORCEPROP 2 LAST SIG_NAME LED_POSTCODE_1
J 0
(-7425 4510);
DISPLAY 0.617021 (-7425 4510);
PAINT ORANGE (-7425 4510);
WIRE 3 682 (-4475 2950)(-4475 2500);
WIRE 3 682 (-3900 2950)(-4475 2950);
WIRE 3 682 (-4475 2500)(-3900 2500);
WIRE 3 682 (-3900 2500)(-3900 2950);
WIRE 16 -1 (-5950 2350)(-5950 2300);
WIRE 16 -1 (-5950 2475)(-5950 2350);
WIRE 16 -1 (-4850 2350)(-5950 2350);
FORCEPROP 2 LAST SIG_NAME FM_CPLD_DBG_PWR_EN
J 0
(-5585 2360);
DISPLAY 0.617021 (-5585 2360);
PAINT ORANGE (-5585 2360);
FORCEPROP 2 LASTPROP $XRERR UNIQUE?
J 0
(-5825 2360);
DISPLAY 0.638298 (-5825 2360);
PAINT MONO (-5825 2360);
DISPLAY INVISIBLE (-5825 2360);
WIRE 16 -1 (-4850 2350)(-4850 2425);
WIRE 16 -1 (-7650 2000)(-7150 2000);
FORCEPROP 2 LAST SIG_NAME FM_CPLD_DBG_PWR_EN_N
J 0
(-7660 2010);
DISPLAY 0.617021 (-7660 2010);
PAINT ORANGE (-7660 2010);
WIRE 16 -1 (-6150 2000)(-6950 2000);
FORCEPROP 2 LAST SIG_NAME FM_CPLD_DBG_PWR_EN_R_N
J 0
(-6785 2010);
DISPLAY 0.617021 (-6785 2010);
PAINT ORANGE (-6785 2010);
FORCEPROP 2 LASTPROP $XRERR UNIQUE?
J 0
(-7025 2010);
DISPLAY 0.638298 (-7025 2010);
PAINT MONO (-7025 2010);
DISPLAY INVISIBLE (-7025 2010);
WIRE 16 -1 (-4750 2625)(-4425 2625);
FORCEPROP 0 LAST VOLTAGE 5
J 0
(-4775 2650);
DISPLAY 1.021277 (-4775 2650);
PAINT SKYBLUE (-4775 2650);
DISPLAY INVISIBLE (-4775 2650);
FORCEPROP 2 LAST SIG_NAME P5V_STBY_DBG
J 0
(-4785 2585);
DISPLAY 0.617021 (-4785 2585);
PAINT ORANGE (-4785 2585);
FORCEPROP 2 LASTPROP $XRERR UNIQUE?
J 0
(-5025 2585);
DISPLAY 0.638298 (-5025 2585);
PAINT MONO (-5025 2585);
DISPLAY INVISIBLE (-5025 2585);
WIRE 16 -1 (-7425 4650)(-7000 4650);
FORCEPROP 2 LAST SIG_NAME LED_POSTCODE_0
J 0
(-7425 4660);
DISPLAY 0.617021 (-7425 4660);
PAINT ORANGE (-7425 4660);
WIRE 16 -1 (-6800 4650)(-6100 4650);
FORCEPROP 2 LAST SIG_NAME LED_POSTCODE_0_R
J 0
(-6450 4660);
DISPLAY 0.617021 (-6450 4660);
PAINT ORANGE (-6450 4660);
WIRE 16 -1 (-6800 4200)(-6100 4200);
FORCEPROP 2 LAST SIG_NAME LED_POSTCODE_3_R
J 0
(-6450 4210);
DISPLAY 0.617021 (-6450 4210);
PAINT ORANGE (-6450 4210);
WIRE 16 -1 (-6800 3900)(-6100 3900);
FORCEPROP 2 LAST SIG_NAME LED_POSTCODE_5_R
J 0
(-6450 3910);
DISPLAY 0.617021 (-6450 3910);
PAINT ORANGE (-6450 3910);
WIRE 16 -1 (-6800 3750)(-6100 3750);
FORCEPROP 2 LAST SIG_NAME LED_POSTCODE_6_R
J 0
(-6450 3760);
DISPLAY 0.617021 (-6450 3760);
PAINT ORANGE (-6450 3760);
WIRE 16 -1 (-5400 1500)(-4750 1500);
FORCEPROP 2 LAST SIG_NAME LED_POSTCODE_4_R
J 0
(-5425 1510);
DISPLAY 0.617021 (-5425 1510);
PAINT ORANGE (-5425 1510);
WIRE 16 -1 (-5400 1450)(-4750 1450);
FORCEPROP 2 LAST SIG_NAME LED_POSTCODE_6_R
J 0
(-5425 1460);
DISPLAY 0.617021 (-5425 1460);
PAINT ORANGE (-5425 1460);
WIRE 16 -1 (-6800 3600)(-6100 3600);
FORCEPROP 2 LAST SIG_NAME LED_POSTCODE_7_R
J 0
(-6450 3610);
DISPLAY 0.617021 (-6450 3610);
PAINT ORANGE (-6450 3610);
WIRE 16 -1 (-7425 3600)(-7000 3600);
FORCEPROP 2 LAST SIG_NAME LED_POSTCODE_7
J 0
(-7425 3610);
DISPLAY 0.617021 (-7425 3610);
PAINT ORANGE (-7425 3610);
WIRE 16 -1 (-7425 4050)(-7000 4050);
FORCEPROP 2 LAST SIG_NAME LED_POSTCODE_4
J 0
(-7425 4060);
DISPLAY 0.617021 (-7425 4060);
PAINT ORANGE (-7425 4060);
WIRE 16 -1 (-4150 1600)(-3650 1600);
FORCEPROP 2 LAST SIG_NAME LED_POSTCODE_1_R
J 2
(-3650 1610);
DISPLAY 0.617021 (-3650 1610);
PAINT ORANGE (-3650 1610);
WIRE 16 -1 (-7425 3750)(-7000 3750);
FORCEPROP 2 LAST SIG_NAME LED_POSTCODE_6
J 0
(-7425 3760);
DISPLAY 0.617021 (-7425 3760);
PAINT ORANGE (-7425 3760);
WIRE 16 -1 (-7425 3900)(-7000 3900);
FORCEPROP 2 LAST SIG_NAME LED_POSTCODE_5
J 0
(-7425 3910);
DISPLAY 0.617021 (-7425 3910);
PAINT ORANGE (-7425 3910);
WIRE 16 -1 (-7425 4200)(-7000 4200);
FORCEPROP 2 LAST SIG_NAME LED_POSTCODE_3
J 0
(-7425 4210);
DISPLAY 0.617021 (-7425 4210);
PAINT ORANGE (-7425 4210);
DOT 1 (-2275 1400);
DOT 1 (-2700 1400);
DOT 1 (-1450 1400);
DOT 1 (-1525 1400);
DOT 1 (-3350 850);
DOT 1 (-4100 1300);
DOT 1 (-5950 2350);
FORCENOTE
CHANGE NET NAME FOR RX AND  GATE1123
(-1900 1150) 0;
DISPLAY LEFT (-1900 1150);
DISPLAY 0.638298 (-1900 1150);
PAINT RED (-1900 1150);
FORCENOTE
TP FAB3 ADD DIODE 1027
(-3050 1300) 0;
DISPLAY LEFT (-3050 1300);
DISPLAY 0.638298 (-3050 1300);
PAINT RED (-3050 1300);
FORCENOTE
TP FAB3 CHANGE R9A5 0803
(-3500 700) 0;
DISPLAY LEFT (-3500 700);
DISPLAY 0.638298 (-3500 700);
PAINT RED (-3500 700);
FORCENOTE
TP FAB3 ADD R6W40 0803
(-2850 2025) 0;
DISPLAY LEFT (-2850 2025);
DISPLAY 1.021277 (-2850 2025);
PAINT RED (-2850 2025);
FORCENOTE
TP FAB1 CHANGE R9A5 FRO 20K TO 15K
(-4050 2125) 0;
DISPLAY LEFT (-4050 2125);
DISPLAY 1.021277 (-4050 2125);
PAINT RED (-4050 2125);
FORCENOTE
TP FAB3 CHANGE CONNECTION OF J9A2.9 0803
(-7425 1250) 0;
DISPLAY LEFT (-7425 1250);
DISPLAY 1.021277 (-7425 1250);
PAINT RED (-7425 1250);
FORCENOTE
TP FAB1 CHANGE FUSE 0428
(-4050 2425) 0;
DISPLAY LEFT (-4050 2425);
DISPLAY 1.021277 (-4050 2425);
PAINT RED (-4050 2425);
FORCENOTE
ROOM=MIO_VIDEO
(-7909 165) 0;
DISPLAY LEFT (-7909 165);
DISPLAY 0.617021 (-7909 165);
PAINT PURPLE (-7909 165);
FORCENOTE
0.5A 8V
(-3825 2800) 0;
DISPLAY LEFT (-3825 2800);
DISPLAY 1.021277 (-3825 2800);
PAINT PURPLE (-3825 2800);
FORCENOTE
1119
(-4025 2050) 0;
DISPLAY LEFT (-4025 2050);
DISPLAY 1.021277 (-4025 2050);
PAINT PURPLE (-4025 2050);
FORCENOTE
TP FAB1 RESERVE R6W19 1119
(-2050 2125) 0;
DISPLAY LEFT (-2050 2125);
DISPLAY 1.021277 (-2050 2125);
PAINT RED (-2050 2125);
FORCENOTE
$CDS_IMAGE|dbg_pwr_en_truth_table_edited_20150327.JPG|3263|763
(-3625 4325) 0;
DISPLAY LEFT (-3625 4325);
QUIT
